FILE_TYPE = MACRO_DRAWING;
SET COLOR_WIRE YELLOW;
SET COLOR_PROP ORANGE;
SET COLOR_DOT WHITE;
SET COLOR_ARC YELLOW;
SET COLOR_BODY GREEN;
SET COLOR_NOTE PURPLE;
SET PROP_DISPLAY VALUE;
SET PAGE_NUMBER P36;
FORCEADD SOCKET4677_AZIF0045P001C01CS..26
(-1000 1375);
FORCEPROP 1 LAST PART_NUMBER DGA^7000023
J 0
(-2050 3475);
DISPLAY 0.723404 (-2050 3475);
PAINT GREEN (-2050 3475);
DISPLAY INVISIBLE (-2050 3475);
FORCEPROP 2 LAST VALUE SOCKET4677_AZIF0045-P001C01CS
J 0
(-2050 3600);
DISPLAY 1.021277 (-2050 3600);
FORCEPROP 1 LAST MATERIAL IO
J 0
(-2050 3400);
DISPLAY 0.723404 (-2050 3400);
PAINT GREEN (-2050 3400);
FORCEPROP 2 LAST PART_TYPE SMLF
J 0
(-2050 3650);
DISPLAY 1.021277 (-2050 3650);
FORCEPROP 1 LAST $LOCATION U2
J 0
(-2050 3550);
DISPLAY 0.723404 (-2050 3550);
PAINT GREEN (-2050 3550);
FORCEPROP 0 LASTPIN (200 -475) $PN BW80
J 0
(210 -465);
DISPLAY 0.680851 (210 -465);
PAINT MONO (210 -465);
FORCEPROP 0 LASTPIN (200 -425) $PN BW82
J 0
(210 -415);
DISPLAY 0.680851 (210 -415);
PAINT MONO (210 -415);
FORCEPROP 0 LASTPIN (200 -375) $PN BW84
J 0
(210 -365);
DISPLAY 0.680851 (210 -365);
PAINT MONO (210 -365);
FORCEPROP 0 LASTPIN (200 -325) $PN BW86
J 0
(210 -315);
DISPLAY 0.680851 (210 -315);
PAINT MONO (210 -315);
FORCEPROP 0 LASTPIN (200 -275) $PN BW88
J 0
(210 -265);
DISPLAY 0.680851 (210 -265);
PAINT MONO (210 -265);
FORCEPROP 0 LASTPIN (200 -225) $PN BW90
J 0
(210 -215);
DISPLAY 0.680851 (210 -215);
PAINT MONO (210 -215);
FORCEPROP 0 LASTPIN (200 -175) $PN BY32
J 0
(210 -165);
DISPLAY 0.680851 (210 -165);
PAINT MONO (210 -165);
FORCEPROP 0 LASTPIN (200 -125) $PN BY34
J 0
(210 -115);
DISPLAY 0.680851 (210 -115);
PAINT MONO (210 -115);
FORCEPROP 0 LASTPIN (200 -75) $PN BY36
J 0
(210 -65);
DISPLAY 0.680851 (210 -65);
PAINT MONO (210 -65);
FORCEPROP 0 LASTPIN (200 -25) $PN BY38
J 0
(210 -15);
DISPLAY 0.680851 (210 -15);
PAINT MONO (210 -15);
FORCEPROP 0 LASTPIN (200 25) $PN BY40
J 0
(210 35);
DISPLAY 0.680851 (210 35);
PAINT MONO (210 35);
FORCEPROP 0 LASTPIN (200 75) $PN BY42
J 0
(210 85);
DISPLAY 0.680851 (210 85);
PAINT MONO (210 85);
FORCEPROP 0 LASTPIN (200 125) $PN BY44
J 0
(210 135);
DISPLAY 0.680851 (210 135);
PAINT MONO (210 135);
FORCEPROP 0 LASTPIN (200 175) $PN BY47
J 0
(210 185);
DISPLAY 0.680851 (210 185);
PAINT MONO (210 185);
FORCEPROP 0 LASTPIN (200 225) $PN BY49
J 0
(210 235);
DISPLAY 0.680851 (210 235);
PAINT MONO (210 235);
FORCEPROP 0 LASTPIN (200 275) $PN BY51
J 0
(210 285);
DISPLAY 0.680851 (210 285);
PAINT MONO (210 285);
FORCEPROP 0 LASTPIN (200 325) $PN BY53
J 0
(210 335);
DISPLAY 0.680851 (210 335);
PAINT MONO (210 335);
FORCEPROP 0 LASTPIN (200 375) $PN BY55
J 0
(210 385);
DISPLAY 0.680851 (210 385);
PAINT MONO (210 385);
FORCEPROP 0 LASTPIN (200 425) $PN BY57
J 0
(210 435);
DISPLAY 0.680851 (210 435);
PAINT MONO (210 435);
FORCEPROP 0 LASTPIN (200 475) $PN BY59
J 0
(210 485);
DISPLAY 0.680851 (210 485);
PAINT MONO (210 485);
FORCEPROP 0 LASTPIN (200 525) $PN BY61
J 0
(210 535);
DISPLAY 0.680851 (210 535);
PAINT MONO (210 535);
FORCEPROP 0 LASTPIN (200 575) $PN BY63
J 0
(210 585);
DISPLAY 0.680851 (210 585);
PAINT MONO (210 585);
FORCEPROP 0 LASTPIN (200 625) $PN BY65
J 0
(210 635);
DISPLAY 0.680851 (210 635);
PAINT MONO (210 635);
FORCEPROP 0 LASTPIN (200 675) $PN BY67
J 0
(210 685);
DISPLAY 0.680851 (210 685);
PAINT MONO (210 685);
FORCEPROP 0 LASTPIN (200 725) $PN BY69
J 0
(210 735);
DISPLAY 0.680851 (210 735);
PAINT MONO (210 735);
FORCEPROP 0 LASTPIN (200 775) $PN BY71
J 0
(210 785);
DISPLAY 0.680851 (210 785);
PAINT MONO (210 785);
FORCEPROP 0 LASTPIN (200 825) $PN BY73
J 0
(210 835);
DISPLAY 0.680851 (210 835);
PAINT MONO (210 835);
FORCEPROP 0 LASTPIN (200 875) $PN BY75
J 0
(210 885);
DISPLAY 0.680851 (210 885);
PAINT MONO (210 885);
FORCEPROP 0 LASTPIN (200 925) $PN BY77
J 0
(210 935);
DISPLAY 0.680851 (210 935);
PAINT MONO (210 935);
FORCEPROP 0 LASTPIN (200 975) $PN BY79
J 0
(210 985);
DISPLAY 0.680851 (210 985);
PAINT MONO (210 985);
FORCEPROP 0 LASTPIN (200 1025) $PN BY81
J 0
(210 1035);
DISPLAY 0.680851 (210 1035);
PAINT MONO (210 1035);
FORCEPROP 0 LASTPIN (200 1075) $PN BY83
J 0
(210 1085);
DISPLAY 0.680851 (210 1085);
PAINT MONO (210 1085);
FORCEPROP 0 LASTPIN (200 1125) $PN BY85
J 0
(210 1135);
DISPLAY 0.680851 (210 1135);
PAINT MONO (210 1135);
FORCEPROP 0 LASTPIN (200 1175) $PN BY87
J 0
(210 1185);
DISPLAY 0.680851 (210 1185);
PAINT MONO (210 1185);
FORCEPROP 0 LASTPIN (200 1225) $PN BY89
J 0
(210 1235);
DISPLAY 0.680851 (210 1235);
PAINT MONO (210 1235);
FORCEPROP 0 LASTPIN (200 1275) $PN CA33
J 0
(210 1285);
DISPLAY 0.680851 (210 1285);
PAINT MONO (210 1285);
FORCEPROP 0 LASTPIN (200 1325) $PN CA35
J 0
(210 1335);
DISPLAY 0.680851 (210 1335);
PAINT MONO (210 1335);
FORCEPROP 0 LASTPIN (200 1375) $PN CA37
J 0
(210 1385);
DISPLAY 0.680851 (210 1385);
PAINT MONO (210 1385);
FORCEPROP 0 LASTPIN (200 1425) $PN CA39
J 0
(210 1435);
DISPLAY 0.680851 (210 1435);
PAINT MONO (210 1435);
FORCEPROP 0 LASTPIN (200 1475) $PN CA41
J 0
(210 1485);
DISPLAY 0.680851 (210 1485);
PAINT MONO (210 1485);
FORCEPROP 0 LASTPIN (200 1525) $PN CA43
J 0
(210 1535);
DISPLAY 0.680851 (210 1535);
PAINT MONO (210 1535);
FORCEPROP 0 LASTPIN (200 1575) $PN CA45
J 0
(210 1585);
DISPLAY 0.680851 (210 1585);
PAINT MONO (210 1585);
FORCEPROP 0 LASTPIN (200 1625) $PN CA48
J 0
(210 1635);
DISPLAY 0.680851 (210 1635);
PAINT MONO (210 1635);
FORCEPROP 0 LASTPIN (200 1675) $PN CA50
J 0
(210 1685);
DISPLAY 0.680851 (210 1685);
PAINT MONO (210 1685);
FORCEPROP 0 LASTPIN (200 1725) $PN CA52
J 0
(210 1735);
DISPLAY 0.680851 (210 1735);
PAINT MONO (210 1735);
FORCEPROP 0 LASTPIN (200 1775) $PN CA54
J 0
(210 1785);
DISPLAY 0.680851 (210 1785);
PAINT MONO (210 1785);
FORCEPROP 0 LASTPIN (200 1825) $PN CA56
J 0
(210 1835);
DISPLAY 0.680851 (210 1835);
PAINT MONO (210 1835);
FORCEPROP 0 LASTPIN (200 1875) $PN CA58
J 0
(210 1885);
DISPLAY 0.680851 (210 1885);
PAINT MONO (210 1885);
FORCEPROP 0 LASTPIN (200 1925) $PN CA60
J 0
(210 1935);
DISPLAY 0.680851 (210 1935);
PAINT MONO (210 1935);
FORCEPROP 0 LASTPIN (200 1975) $PN CA62
J 0
(210 1985);
DISPLAY 0.680851 (210 1985);
PAINT MONO (210 1985);
FORCEPROP 0 LASTPIN (200 2025) $PN CA64
J 0
(210 2035);
DISPLAY 0.680851 (210 2035);
PAINT MONO (210 2035);
FORCEPROP 0 LASTPIN (200 2075) $PN CA66
J 0
(210 2085);
DISPLAY 0.680851 (210 2085);
PAINT MONO (210 2085);
FORCEPROP 0 LASTPIN (200 2125) $PN CA68
J 0
(210 2135);
DISPLAY 0.680851 (210 2135);
PAINT MONO (210 2135);
FORCEPROP 0 LASTPIN (200 2175) $PN CA70
J 0
(210 2185);
DISPLAY 0.680851 (210 2185);
PAINT MONO (210 2185);
FORCEPROP 0 LASTPIN (200 2225) $PN CA72
J 0
(210 2235);
DISPLAY 0.680851 (210 2235);
PAINT MONO (210 2235);
FORCEPROP 0 LASTPIN (200 2275) $PN CA74
J 0
(210 2285);
DISPLAY 0.680851 (210 2285);
PAINT MONO (210 2285);
FORCEPROP 0 LASTPIN (200 2325) $PN CA76
J 0
(210 2335);
DISPLAY 0.680851 (210 2335);
PAINT MONO (210 2335);
FORCEPROP 0 LASTPIN (200 2375) $PN CA78
J 0
(210 2385);
DISPLAY 0.680851 (210 2385);
PAINT MONO (210 2385);
FORCEPROP 0 LASTPIN (200 2425) $PN CA80
J 0
(210 2435);
DISPLAY 0.680851 (210 2435);
PAINT MONO (210 2435);
FORCEPROP 0 LASTPIN (200 2475) $PN CA82
J 0
(210 2485);
DISPLAY 0.680851 (210 2485);
PAINT MONO (210 2485);
FORCEPROP 0 LASTPIN (200 2525) $PN CA84
J 0
(210 2535);
DISPLAY 0.680851 (210 2535);
PAINT MONO (210 2535);
FORCEPROP 0 LASTPIN (200 2575) $PN CA86
J 0
(210 2585);
DISPLAY 0.680851 (210 2585);
PAINT MONO (210 2585);
FORCEPROP 0 LASTPIN (200 2625) $PN CA88
J 0
(210 2635);
DISPLAY 0.680851 (210 2635);
PAINT MONO (210 2635);
FORCEPROP 0 LASTPIN (200 2675) $PN CA90
J 0
(210 2685);
DISPLAY 0.680851 (210 2685);
PAINT MONO (210 2685);
FORCEPROP 0 LASTPIN (200 2725) $PN CB61
J 0
(210 2735);
DISPLAY 0.680851 (210 2735);
PAINT MONO (210 2735);
FORCEPROP 0 LASTPIN (200 2775) $PN CB75
J 0
(210 2785);
DISPLAY 0.680851 (210 2785);
PAINT MONO (210 2785);
FORCEPROP 0 LASTPIN (200 2825) $PN CB77
J 0
(210 2835);
DISPLAY 0.680851 (210 2835);
PAINT MONO (210 2835);
FORCEPROP 0 LASTPIN (200 2875) $PN CC33
J 0
(210 2885);
DISPLAY 0.680851 (210 2885);
PAINT MONO (210 2885);
FORCEPROP 0 LASTPIN (200 2925) $PN CC35
J 0
(210 2935);
DISPLAY 0.680851 (210 2935);
PAINT MONO (210 2935);
FORCEPROP 0 LASTPIN (200 2975) $PN CC37
J 0
(210 2985);
DISPLAY 0.680851 (210 2985);
PAINT MONO (210 2985);
FORCEPROP 0 LASTPIN (200 3025) $PN CC39
J 0
(210 3035);
DISPLAY 0.680851 (210 3035);
PAINT MONO (210 3035);
FORCEPROP 0 LASTPIN (200 3075) $PN CC41
J 0
(210 3085);
DISPLAY 0.680851 (210 3085);
PAINT MONO (210 3085);
FORCEPROP 0 LASTPIN (200 3125) $PN CC43
J 0
(210 3135);
DISPLAY 0.680851 (210 3135);
PAINT MONO (210 3135);
FORCEPROP 0 LASTPIN (200 3175) $PN CC45
J 0
(210 3185);
DISPLAY 0.680851 (210 3185);
PAINT MONO (210 3185);
FORCEPROP 0 LASTPIN (200 3225) $PN CC48
J 0
(210 3235);
DISPLAY 0.680851 (210 3235);
PAINT MONO (210 3235);
FORCEPROP 0 LASTPIN (-2200 -475) $PN CC50
J 2
(-2210 -465);
DISPLAY 0.680851 (-2210 -465);
PAINT MONO (-2210 -465);
FORCEPROP 0 LASTPIN (-2200 -425) $PN CC52
J 2
(-2210 -415);
DISPLAY 0.680851 (-2210 -415);
PAINT MONO (-2210 -415);
FORCEPROP 0 LASTPIN (-2200 -375) $PN CC54
J 2
(-2210 -365);
DISPLAY 0.680851 (-2210 -365);
PAINT MONO (-2210 -365);
FORCEPROP 0 LASTPIN (-2200 -325) $PN CC56
J 2
(-2210 -315);
DISPLAY 0.680851 (-2210 -315);
PAINT MONO (-2210 -315);
FORCEPROP 0 LASTPIN (-2200 -275) $PN CC58
J 2
(-2210 -265);
DISPLAY 0.680851 (-2210 -265);
PAINT MONO (-2210 -265);
FORCEPROP 0 LASTPIN (-2200 -225) $PN CC60
J 2
(-2210 -215);
DISPLAY 0.680851 (-2210 -215);
PAINT MONO (-2210 -215);
FORCEPROP 0 LASTPIN (-2200 -175) $PN CC76
J 2
(-2210 -165);
DISPLAY 0.680851 (-2210 -165);
PAINT MONO (-2210 -165);
FORCEPROP 0 LASTPIN (-2200 -125) $PN CC78
J 2
(-2210 -115);
DISPLAY 0.680851 (-2210 -115);
PAINT MONO (-2210 -115);
FORCEPROP 0 LASTPIN (-2200 -75) $PN CC80
J 2
(-2210 -65);
DISPLAY 0.680851 (-2210 -65);
PAINT MONO (-2210 -65);
FORCEPROP 0 LASTPIN (-2200 -25) $PN CC82
J 2
(-2210 -15);
DISPLAY 0.680851 (-2210 -15);
PAINT MONO (-2210 -15);
FORCEPROP 0 LASTPIN (-2200 25) $PN CC84
J 2
(-2210 35);
DISPLAY 0.680851 (-2210 35);
PAINT MONO (-2210 35);
FORCEPROP 0 LASTPIN (-2200 75) $PN CC86
J 2
(-2210 85);
DISPLAY 0.680851 (-2210 85);
PAINT MONO (-2210 85);
FORCEPROP 0 LASTPIN (-2200 125) $PN CC88
J 2
(-2210 135);
DISPLAY 0.680851 (-2210 135);
PAINT MONO (-2210 135);
FORCEPROP 0 LASTPIN (-2200 175) $PN CC90
J 2
(-2210 185);
DISPLAY 0.680851 (-2210 185);
PAINT MONO (-2210 185);
FORCEPROP 0 LASTPIN (-2200 225) $PN CD32
J 2
(-2210 235);
DISPLAY 0.680851 (-2210 235);
PAINT MONO (-2210 235);
FORCEPROP 0 LASTPIN (-2200 275) $PN CD34
J 2
(-2210 285);
DISPLAY 0.680851 (-2210 285);
PAINT MONO (-2210 285);
FORCEPROP 0 LASTPIN (-2200 325) $PN CD36
J 2
(-2210 335);
DISPLAY 0.680851 (-2210 335);
PAINT MONO (-2210 335);
FORCEPROP 0 LASTPIN (-2200 375) $PN CD38
J 2
(-2210 385);
DISPLAY 0.680851 (-2210 385);
PAINT MONO (-2210 385);
FORCEPROP 0 LASTPIN (-2200 425) $PN CD40
J 2
(-2210 435);
DISPLAY 0.680851 (-2210 435);
PAINT MONO (-2210 435);
FORCEPROP 0 LASTPIN (-2200 475) $PN CD42
J 2
(-2210 485);
DISPLAY 0.680851 (-2210 485);
PAINT MONO (-2210 485);
FORCEPROP 0 LASTPIN (-2200 525) $PN CD44
J 2
(-2210 535);
DISPLAY 0.680851 (-2210 535);
PAINT MONO (-2210 535);
FORCEPROP 0 LASTPIN (-2200 575) $PN CD47
J 2
(-2210 585);
DISPLAY 0.680851 (-2210 585);
PAINT MONO (-2210 585);
FORCEPROP 0 LASTPIN (-2200 625) $PN CD49
J 2
(-2210 635);
DISPLAY 0.680851 (-2210 635);
PAINT MONO (-2210 635);
FORCEPROP 0 LASTPIN (-2200 675) $PN CD51
J 2
(-2210 685);
DISPLAY 0.680851 (-2210 685);
PAINT MONO (-2210 685);
FORCEPROP 0 LASTPIN (-2200 725) $PN CD53
J 2
(-2210 735);
DISPLAY 0.680851 (-2210 735);
PAINT MONO (-2210 735);
FORCEPROP 0 LASTPIN (-2200 775) $PN CD55
J 2
(-2210 785);
DISPLAY 0.680851 (-2210 785);
PAINT MONO (-2210 785);
FORCEPROP 0 LASTPIN (-2200 825) $PN CD57
J 2
(-2210 835);
DISPLAY 0.680851 (-2210 835);
PAINT MONO (-2210 835);
FORCEPROP 0 LASTPIN (-2200 875) $PN CD59
J 2
(-2210 885);
DISPLAY 0.680851 (-2210 885);
PAINT MONO (-2210 885);
FORCEPROP 0 LASTPIN (-2200 925) $PN CD79
J 2
(-2210 935);
DISPLAY 0.680851 (-2210 935);
PAINT MONO (-2210 935);
FORCEPROP 0 LASTPIN (-2200 975) $PN CD81
J 2
(-2210 985);
DISPLAY 0.680851 (-2210 985);
PAINT MONO (-2210 985);
FORCEPROP 0 LASTPIN (-2200 1025) $PN CD83
J 2
(-2210 1035);
DISPLAY 0.680851 (-2210 1035);
PAINT MONO (-2210 1035);
FORCEPROP 0 LASTPIN (-2200 1075) $PN CD85
J 2
(-2210 1085);
DISPLAY 0.680851 (-2210 1085);
PAINT MONO (-2210 1085);
FORCEPROP 0 LASTPIN (-2200 1125) $PN CD87
J 2
(-2210 1135);
DISPLAY 0.680851 (-2210 1135);
PAINT MONO (-2210 1135);
FORCEPROP 0 LASTPIN (-2200 1175) $PN CD89
J 2
(-2210 1185);
DISPLAY 0.680851 (-2210 1185);
PAINT MONO (-2210 1185);
FORCEPROP 0 LASTPIN (-2200 1225) $PN CE80
J 2
(-2210 1235);
DISPLAY 0.680851 (-2210 1235);
PAINT MONO (-2210 1235);
FORCEPROP 0 LASTPIN (-2200 1275) $PN CE82
J 2
(-2210 1285);
DISPLAY 0.680851 (-2210 1285);
PAINT MONO (-2210 1285);
FORCEPROP 0 LASTPIN (-2200 1325) $PN CE84
J 2
(-2210 1335);
DISPLAY 0.680851 (-2210 1335);
PAINT MONO (-2210 1335);
FORCEPROP 0 LASTPIN (-2200 1375) $PN CE86
J 2
(-2210 1385);
DISPLAY 0.680851 (-2210 1385);
PAINT MONO (-2210 1385);
FORCEPROP 0 LASTPIN (-2200 1425) $PN CE88
J 2
(-2210 1435);
DISPLAY 0.680851 (-2210 1435);
PAINT MONO (-2210 1435);
FORCEPROP 0 LASTPIN (-2200 1475) $PN CE90
J 2
(-2210 1485);
DISPLAY 0.680851 (-2210 1485);
PAINT MONO (-2210 1485);
FORCEPROP 0 LASTPIN (-2200 1525) $PN CF79
J 2
(-2210 1535);
DISPLAY 0.680851 (-2210 1535);
PAINT MONO (-2210 1535);
FORCEPROP 0 LASTPIN (-2200 1575) $PN CF81
J 2
(-2210 1585);
DISPLAY 0.680851 (-2210 1585);
PAINT MONO (-2210 1585);
FORCEPROP 0 LASTPIN (-2200 1625) $PN CF83
J 2
(-2210 1635);
DISPLAY 0.680851 (-2210 1635);
PAINT MONO (-2210 1635);
FORCEPROP 0 LASTPIN (-2200 1675) $PN CF85
J 2
(-2210 1685);
DISPLAY 0.680851 (-2210 1685);
PAINT MONO (-2210 1685);
FORCEPROP 0 LASTPIN (-2200 1725) $PN CF87
J 2
(-2210 1735);
DISPLAY 0.680851 (-2210 1735);
PAINT MONO (-2210 1735);
FORCEPROP 0 LASTPIN (-2200 1775) $PN CF89
J 2
(-2210 1785);
DISPLAY 0.680851 (-2210 1785);
PAINT MONO (-2210 1785);
FORCEPROP 0 LASTPIN (-2200 1825) $PN CF91
J 2
(-2210 1835);
DISPLAY 0.680851 (-2210 1835);
PAINT MONO (-2210 1835);
FORCEPROP 0 LASTPIN (-2200 1875) $PN CG80
J 2
(-2210 1885);
DISPLAY 0.680851 (-2210 1885);
PAINT MONO (-2210 1885);
FORCEPROP 0 LASTPIN (-2200 1925) $PN CG82
J 2
(-2210 1935);
DISPLAY 0.680851 (-2210 1935);
PAINT MONO (-2210 1935);
FORCEPROP 0 LASTPIN (-2200 1975) $PN CG84
J 2
(-2210 1985);
DISPLAY 0.680851 (-2210 1985);
PAINT MONO (-2210 1985);
FORCEPROP 0 LASTPIN (-2200 2025) $PN CG86
J 2
(-2210 2035);
DISPLAY 0.680851 (-2210 2035);
PAINT MONO (-2210 2035);
FORCEPROP 0 LASTPIN (-2200 2075) $PN CG88
J 2
(-2210 2085);
DISPLAY 0.680851 (-2210 2085);
PAINT MONO (-2210 2085);
FORCEPROP 0 LASTPIN (-2200 2125) $PN CG90
J 2
(-2210 2135);
DISPLAY 0.680851 (-2210 2135);
PAINT MONO (-2210 2135);
FORCEPROP 0 LASTPIN (-2200 2175) $PN CH81
J 2
(-2210 2185);
DISPLAY 0.680851 (-2210 2185);
PAINT MONO (-2210 2185);
FORCEPROP 0 LASTPIN (-2200 2225) $PN CH91
J 2
(-2210 2235);
DISPLAY 0.680851 (-2210 2235);
PAINT MONO (-2210 2235);
FORCEPROP 0 LASTPIN (-2200 2275) $PN CJ82
J 2
(-2210 2285);
DISPLAY 0.680851 (-2210 2285);
PAINT MONO (-2210 2285);
FORCEPROP 0 LASTPIN (-2200 2325) $PN CJ84
J 2
(-2210 2335);
DISPLAY 0.680851 (-2210 2335);
PAINT MONO (-2210 2335);
FORCEPROP 0 LASTPIN (-2200 2375) $PN CJ86
J 2
(-2210 2385);
DISPLAY 0.680851 (-2210 2385);
PAINT MONO (-2210 2385);
FORCEPROP 0 LASTPIN (-2200 2425) $PN CJ88
J 2
(-2210 2435);
DISPLAY 0.680851 (-2210 2435);
PAINT MONO (-2210 2435);
FORCEPROP 0 LASTPIN (-2200 2475) $PN CJ90
J 2
(-2210 2485);
DISPLAY 0.680851 (-2210 2485);
PAINT MONO (-2210 2485);
FORCEPROP 0 LASTPIN (-2200 2525) $PN CK83
J 2
(-2210 2535);
DISPLAY 0.680851 (-2210 2535);
PAINT MONO (-2210 2535);
FORCEPROP 0 LASTPIN (-2200 2575) $PN CK85
J 2
(-2210 2585);
DISPLAY 0.680851 (-2210 2585);
PAINT MONO (-2210 2585);
FORCEPROP 0 LASTPIN (-2200 2625) $PN CK87
J 2
(-2210 2635);
DISPLAY 0.680851 (-2210 2635);
PAINT MONO (-2210 2635);
FORCEPROP 0 LASTPIN (-2200 2675) $PN CK89
J 2
(-2210 2685);
DISPLAY 0.680851 (-2210 2685);
PAINT MONO (-2210 2685);
FORCEPROP 0 LASTPIN (-2200 2725) $PN CK91
J 2
(-2210 2735);
DISPLAY 0.680851 (-2210 2735);
PAINT MONO (-2210 2735);
FORCEPROP 0 LASTPIN (-2200 2775) $PN CL84
J 2
(-2210 2785);
DISPLAY 0.680851 (-2210 2785);
PAINT MONO (-2210 2785);
FORCEPROP 0 LASTPIN (-2200 2825) $PN CL86
J 2
(-2210 2835);
DISPLAY 0.680851 (-2210 2835);
PAINT MONO (-2210 2835);
FORCEPROP 0 LASTPIN (-2200 2875) $PN CL88
J 2
(-2210 2885);
DISPLAY 0.680851 (-2210 2885);
PAINT MONO (-2210 2885);
FORCEPROP 0 LASTPIN (-2200 2925) $PN CL90
J 2
(-2210 2935);
DISPLAY 0.680851 (-2210 2935);
PAINT MONO (-2210 2935);
FORCEPROP 0 LASTPIN (-2200 2975) $PN CM87
J 2
(-2210 2985);
DISPLAY 0.680851 (-2210 2985);
PAINT MONO (-2210 2985);
FORCEPROP 0 LASTPIN (-2200 3075) $PN CM91
J 2
(-2210 3085);
DISPLAY 0.680851 (-2210 3085);
PAINT MONO (-2210 3085);
FORCEPROP 0 LASTPIN (-2200 3125) $PN CN88
J 2
(-2210 3135);
DISPLAY 0.680851 (-2210 3135);
PAINT MONO (-2210 3135);
FORCEPROP 0 LASTPIN (-2200 3175) $PN CN90
J 2
(-2210 3185);
DISPLAY 0.680851 (-2210 3185);
PAINT MONO (-2210 3185);
FORCEPROP 0 LASTPIN (-2200 3225) $PN CP89
J 2
(-2210 3235);
DISPLAY 0.680851 (-2210 3235);
PAINT MONO (-2210 3235);
FORCEPROP 0 LASTPIN (-2200 3025) $PN CM89
J 2
(-2210 3035);
DISPLAY 0.680851 (-2210 3035);
PAINT MONO (-2210 3035);
FORCEPROP 1 LAST CDS_LMAN_SYM_OUTLINE -1050,2000,1050,-2000
J 0
(-1000 1375);
DISPLAY 0.468085 (-1000 1375);
PAINT GREEN (-1000 1375);
DISPLAY INVISIBLE (-1000 1375);
FORCEPROP 1 LAST NEEDS_NO_SIZE TRUE
J 0
(-1000 1375);
DISPLAY 0.723404 (-1000 1375);
PAINT GREEN (-1000 1375);
DISPLAY INVISIBLE (-1000 1375);
FORCEPROP 2 LAST CDS_LIB pure_quanta
J 0
(-1000 1375);
DISPLAY INVISIBLE (-1000 1375);
FORCEPROP 2 LAST CDS_LOCATION U2
J 0
(-2050 3700);
DISPLAY 1.021277 (-2050 3700);
DISPLAY INVISIBLE (-2050 3700);
FORCEPROP 0 LAST $SEC 26
J 0
(-2050 3700);
DISPLAY 0.680851 (-2050 3700);
PAINT MONO (-2050 3700);
DISPLAY INVISIBLE (-2050 3700);
FORCEPROP 2 LAST CDS_SEC 26
J 0
(-2050 3700);
DISPLAY 1.021277 (-2050 3700);
DISPLAY INVISIBLE (-2050 3700);
FORCEPROP 1 LAST PATH I1
J 0
(-1000 1375);
DISPLAY 0.723404 (-1000 1375);
PAINT GREEN (-1000 1375);
DISPLAY INVISIBLE (-1000 1375);
FORCEADD VCC_CORE..1
(-2450 3450);
FORCEPROP 3 LASTPIN (-2450 3400) SIG_NAME PVCCIN_CPU0\g
J 0
(-2440 3410);
DISPLAY 0.659574 (-2440 3410);
PAINT MONO (-2440 3410);
DISPLAY INVISIBLE (-2440 3410);
FORCEPROP 1 LAST HDL_POWER PVCCIN_CPU0
J 1
(-2450 3500);
DISPLAY 1.148936 (-2450 3500);
PAINT GREEN (-2450 3500);
FORCEPROP 2 LAST CDS_LIB logical_power
J 0
(-2450 3450);
PAINT MONO (-2450 3450);
DISPLAY INVISIBLE (-2450 3450);
FORCEPROP 1 LAST PATH I2
J 0
(-2400 3475);
DISPLAY 0.872340 (-2400 3475);
PAINT AQUA (-2400 3475);
DISPLAY INVISIBLE (-2400 3475);
FORCEADD VCC_CORE..1
(450 3450);
FORCEPROP 3 LASTPIN (450 3400) SIG_NAME PVCCIN_CPU0\g
J 0
(460 3410);
DISPLAY 0.659574 (460 3410);
PAINT MONO (460 3410);
DISPLAY INVISIBLE (460 3410);
FORCEPROP 1 LAST HDL_POWER PVCCIN_CPU0
J 1
(450 3500);
DISPLAY 1.148936 (450 3500);
PAINT GREEN (450 3500);
FORCEPROP 2 LAST CDS_LIB logical_power
J 0
(450 3450);
PAINT MONO (450 3450);
DISPLAY INVISIBLE (450 3450);
FORCEPROP 1 LAST PATH I3
J 0
(500 3475);
DISPLAY 0.872340 (500 3475);
PAINT AQUA (500 3475);
DISPLAY INVISIBLE (500 3475);
FORCEADD VCC_CORE..1
(4825 3450);
FORCEPROP 3 LASTPIN (4825 3400) SIG_NAME PVCCIN_CPU0\g
J 0
(4835 3410);
DISPLAY 0.659574 (4835 3410);
PAINT MONO (4835 3410);
DISPLAY INVISIBLE (4835 3410);
FORCEPROP 1 LAST HDL_POWER PVCCIN_CPU0
J 1
(4825 3500);
DISPLAY 1.148936 (4825 3500);
PAINT GREEN (4825 3500);
FORCEPROP 2 LAST CDS_LIB logical_power
J 0
(4825 3450);
PAINT MONO (4825 3450);
DISPLAY INVISIBLE (4825 3450);
FORCEPROP 1 LAST PATH I5
J 0
(4875 3475);
DISPLAY 0.872340 (4875 3475);
PAINT AQUA (4875 3475);
DISPLAY INVISIBLE (4875 3475);
FORCEADD VCC_CORE..1
(1925 3450);
FORCEPROP 3 LASTPIN (1925 3400) SIG_NAME PVCCIN_CPU0\g
J 0
(1935 3410);
DISPLAY 0.659574 (1935 3410);
PAINT MONO (1935 3410);
DISPLAY INVISIBLE (1935 3410);
FORCEPROP 1 LAST HDL_POWER PVCCIN_CPU0
J 1
(1925 3500);
DISPLAY 1.148936 (1925 3500);
PAINT GREEN (1925 3500);
FORCEPROP 2 LAST CDS_LIB logical_power
J 0
(1925 3450);
PAINT MONO (1925 3450);
DISPLAY INVISIBLE (1925 3450);
FORCEPROP 1 LAST PATH I6
J 0
(1975 3475);
DISPLAY 0.872340 (1975 3475);
PAINT AQUA (1975 3475);
DISPLAY INVISIBLE (1975 3475);
FORCEADD SOCKET4677_AZIF0045P001C01CS..27
(3375 1375);
FORCEPROP 1 LAST PART_NUMBER DGA^7000023
J 0
(2325 3475);
DISPLAY 0.723404 (2325 3475);
PAINT GREEN (2325 3475);
DISPLAY INVISIBLE (2325 3475);
FORCEPROP 2 LAST VALUE SOCKET4677_AZIF0045-P001C01CS
J 0
(2325 3600);
DISPLAY 1.021277 (2325 3600);
FORCEPROP 1 LAST MATERIAL IO
J 0
(2325 3400);
DISPLAY 0.723404 (2325 3400);
PAINT GREEN (2325 3400);
FORCEPROP 2 LAST PART_TYPE SMLF
J 0
(2325 3650);
DISPLAY 1.021277 (2325 3650);
FORCEPROP 1 LAST $LOCATION U2
J 0
(2325 3550);
DISPLAY 0.723404 (2325 3550);
PAINT GREEN (2325 3550);
FORCEPROP 0 LASTPIN (4575 -475) $PN BN43
J 0
(4585 -465);
DISPLAY 0.680851 (4585 -465);
PAINT MONO (4585 -465);
FORCEPROP 0 LASTPIN (4575 -425) $PN BN45
J 0
(4585 -415);
DISPLAY 0.680851 (4585 -415);
PAINT MONO (4585 -415);
FORCEPROP 0 LASTPIN (4575 -375) $PN BN48
J 0
(4585 -365);
DISPLAY 0.680851 (4585 -365);
PAINT MONO (4585 -365);
FORCEPROP 0 LASTPIN (4575 -325) $PN BN50
J 0
(4585 -315);
DISPLAY 0.680851 (4585 -315);
PAINT MONO (4585 -315);
FORCEPROP 0 LASTPIN (4575 -275) $PN BN52
J 0
(4585 -265);
DISPLAY 0.680851 (4585 -265);
PAINT MONO (4585 -265);
FORCEPROP 0 LASTPIN (4575 -225) $PN BN54
J 0
(4585 -215);
DISPLAY 0.680851 (4585 -215);
PAINT MONO (4585 -215);
FORCEPROP 0 LASTPIN (4575 -175) $PN BN56
J 0
(4585 -165);
DISPLAY 0.680851 (4585 -165);
PAINT MONO (4585 -165);
FORCEPROP 0 LASTPIN (4575 -125) $PN BN58
J 0
(4585 -115);
DISPLAY 0.680851 (4585 -115);
PAINT MONO (4585 -115);
FORCEPROP 0 LASTPIN (4575 -75) $PN BN60
J 0
(4585 -65);
DISPLAY 0.680851 (4585 -65);
PAINT MONO (4585 -65);
FORCEPROP 0 LASTPIN (4575 -25) $PN BN78
J 0
(4585 -15);
DISPLAY 0.680851 (4585 -15);
PAINT MONO (4585 -15);
FORCEPROP 0 LASTPIN (4575 25) $PN BN80
J 0
(4585 35);
DISPLAY 0.680851 (4585 35);
PAINT MONO (4585 35);
FORCEPROP 0 LASTPIN (4575 75) $PN BN82
J 0
(4585 85);
DISPLAY 0.680851 (4585 85);
PAINT MONO (4585 85);
FORCEPROP 0 LASTPIN (4575 125) $PN BN84
J 0
(4585 135);
DISPLAY 0.680851 (4585 135);
PAINT MONO (4585 135);
FORCEPROP 0 LASTPIN (4575 175) $PN BN86
J 0
(4585 185);
DISPLAY 0.680851 (4585 185);
PAINT MONO (4585 185);
FORCEPROP 0 LASTPIN (4575 225) $PN BN88
J 0
(4585 235);
DISPLAY 0.680851 (4585 235);
PAINT MONO (4585 235);
FORCEPROP 0 LASTPIN (4575 275) $PN BN90
J 0
(4585 285);
DISPLAY 0.680851 (4585 285);
PAINT MONO (4585 285);
FORCEPROP 0 LASTPIN (4575 325) $PN BP32
J 0
(4585 335);
DISPLAY 0.680851 (4585 335);
PAINT MONO (4585 335);
FORCEPROP 0 LASTPIN (4575 375) $PN BP34
J 0
(4585 385);
DISPLAY 0.680851 (4585 385);
PAINT MONO (4585 385);
FORCEPROP 0 LASTPIN (4575 425) $PN BP36
J 0
(4585 435);
DISPLAY 0.680851 (4585 435);
PAINT MONO (4585 435);
FORCEPROP 0 LASTPIN (4575 475) $PN BP38
J 0
(4585 485);
DISPLAY 0.680851 (4585 485);
PAINT MONO (4585 485);
FORCEPROP 0 LASTPIN (4575 525) $PN BP40
J 0
(4585 535);
DISPLAY 0.680851 (4585 535);
PAINT MONO (4585 535);
FORCEPROP 0 LASTPIN (4575 575) $PN BP42
J 0
(4585 585);
DISPLAY 0.680851 (4585 585);
PAINT MONO (4585 585);
FORCEPROP 0 LASTPIN (4575 625) $PN BP44
J 0
(4585 635);
DISPLAY 0.680851 (4585 635);
PAINT MONO (4585 635);
FORCEPROP 0 LASTPIN (4575 675) $PN BP47
J 0
(4585 685);
DISPLAY 0.680851 (4585 685);
PAINT MONO (4585 685);
FORCEPROP 0 LASTPIN (4575 725) $PN BP49
J 0
(4585 735);
DISPLAY 0.680851 (4585 735);
PAINT MONO (4585 735);
FORCEPROP 0 LASTPIN (4575 775) $PN BP51
J 0
(4585 785);
DISPLAY 0.680851 (4585 785);
PAINT MONO (4585 785);
FORCEPROP 0 LASTPIN (4575 825) $PN BP53
J 0
(4585 835);
DISPLAY 0.680851 (4585 835);
PAINT MONO (4585 835);
FORCEPROP 0 LASTPIN (4575 875) $PN BP55
J 0
(4585 885);
DISPLAY 0.680851 (4585 885);
PAINT MONO (4585 885);
FORCEPROP 0 LASTPIN (4575 925) $PN BP57
J 0
(4585 935);
DISPLAY 0.680851 (4585 935);
PAINT MONO (4585 935);
FORCEPROP 0 LASTPIN (4575 975) $PN BP59
J 0
(4585 985);
DISPLAY 0.680851 (4585 985);
PAINT MONO (4585 985);
FORCEPROP 0 LASTPIN (4575 1025) $PN BP61
J 0
(4585 1035);
DISPLAY 0.680851 (4585 1035);
PAINT MONO (4585 1035);
FORCEPROP 0 LASTPIN (4575 1075) $PN BP79
J 0
(4585 1085);
DISPLAY 0.680851 (4585 1085);
PAINT MONO (4585 1085);
FORCEPROP 0 LASTPIN (4575 1125) $PN BP81
J 0
(4585 1135);
DISPLAY 0.680851 (4585 1135);
PAINT MONO (4585 1135);
FORCEPROP 0 LASTPIN (4575 1175) $PN BP83
J 0
(4585 1185);
DISPLAY 0.680851 (4585 1185);
PAINT MONO (4585 1185);
FORCEPROP 0 LASTPIN (4575 1225) $PN BP85
J 0
(4585 1235);
DISPLAY 0.680851 (4585 1235);
PAINT MONO (4585 1235);
FORCEPROP 0 LASTPIN (4575 1275) $PN BP87
J 0
(4585 1285);
DISPLAY 0.680851 (4585 1285);
PAINT MONO (4585 1285);
FORCEPROP 0 LASTPIN (4575 1325) $PN BP89
J 0
(4585 1335);
DISPLAY 0.680851 (4585 1335);
PAINT MONO (4585 1335);
FORCEPROP 0 LASTPIN (4575 1375) $PN BR60
J 0
(4585 1385);
DISPLAY 0.680851 (4585 1385);
PAINT MONO (4585 1385);
FORCEPROP 0 LASTPIN (4575 1425) $PN BR62
J 0
(4585 1435);
DISPLAY 0.680851 (4585 1435);
PAINT MONO (4585 1435);
FORCEPROP 0 LASTPIN (4575 1475) $PN BR78
J 0
(4585 1485);
DISPLAY 0.680851 (4585 1485);
PAINT MONO (4585 1485);
FORCEPROP 0 LASTPIN (4575 1525) $PN BT32
J 0
(4585 1535);
DISPLAY 0.680851 (4585 1535);
PAINT MONO (4585 1535);
FORCEPROP 0 LASTPIN (4575 1575) $PN BT34
J 0
(4585 1585);
DISPLAY 0.680851 (4585 1585);
PAINT MONO (4585 1585);
FORCEPROP 0 LASTPIN (4575 1625) $PN BT36
J 0
(4585 1635);
DISPLAY 0.680851 (4585 1635);
PAINT MONO (4585 1635);
FORCEPROP 0 LASTPIN (4575 1675) $PN BT38
J 0
(4585 1685);
DISPLAY 0.680851 (4585 1685);
PAINT MONO (4585 1685);
FORCEPROP 0 LASTPIN (4575 1725) $PN BT40
J 0
(4585 1735);
DISPLAY 0.680851 (4585 1735);
PAINT MONO (4585 1735);
FORCEPROP 0 LASTPIN (4575 1775) $PN BT42
J 0
(4585 1785);
DISPLAY 0.680851 (4585 1785);
PAINT MONO (4585 1785);
FORCEPROP 0 LASTPIN (4575 1825) $PN BT44
J 0
(4585 1835);
DISPLAY 0.680851 (4585 1835);
PAINT MONO (4585 1835);
FORCEPROP 0 LASTPIN (4575 1875) $PN BT47
J 0
(4585 1885);
DISPLAY 0.680851 (4585 1885);
PAINT MONO (4585 1885);
FORCEPROP 0 LASTPIN (4575 1925) $PN BT49
J 0
(4585 1935);
DISPLAY 0.680851 (4585 1935);
PAINT MONO (4585 1935);
FORCEPROP 0 LASTPIN (4575 1975) $PN BT51
J 0
(4585 1985);
DISPLAY 0.680851 (4585 1985);
PAINT MONO (4585 1985);
FORCEPROP 0 LASTPIN (4575 2025) $PN BT53
J 0
(4585 2035);
DISPLAY 0.680851 (4585 2035);
PAINT MONO (4585 2035);
FORCEPROP 0 LASTPIN (4575 2075) $PN BT55
J 0
(4585 2085);
DISPLAY 0.680851 (4585 2085);
PAINT MONO (4585 2085);
FORCEPROP 0 LASTPIN (4575 2125) $PN BT57
J 0
(4585 2135);
DISPLAY 0.680851 (4585 2135);
PAINT MONO (4585 2135);
FORCEPROP 0 LASTPIN (4575 2175) $PN BT59
J 0
(4585 2185);
DISPLAY 0.680851 (4585 2185);
PAINT MONO (4585 2185);
FORCEPROP 0 LASTPIN (4575 2225) $PN BT61
J 0
(4585 2235);
DISPLAY 0.680851 (4585 2235);
PAINT MONO (4585 2235);
FORCEPROP 0 LASTPIN (4575 2275) $PN BT63
J 0
(4585 2285);
DISPLAY 0.680851 (4585 2285);
PAINT MONO (4585 2285);
FORCEPROP 0 LASTPIN (4575 2325) $PN BT65
J 0
(4585 2335);
DISPLAY 0.680851 (4585 2335);
PAINT MONO (4585 2335);
FORCEPROP 0 LASTPIN (4575 2375) $PN BT67
J 0
(4585 2385);
DISPLAY 0.680851 (4585 2385);
PAINT MONO (4585 2385);
FORCEPROP 0 LASTPIN (4575 2425) $PN BT69
J 0
(4585 2435);
DISPLAY 0.680851 (4585 2435);
PAINT MONO (4585 2435);
FORCEPROP 0 LASTPIN (4575 2475) $PN BT71
J 0
(4585 2485);
DISPLAY 0.680851 (4585 2485);
PAINT MONO (4585 2485);
FORCEPROP 0 LASTPIN (4575 2525) $PN BT73
J 0
(4585 2535);
DISPLAY 0.680851 (4585 2535);
PAINT MONO (4585 2535);
FORCEPROP 0 LASTPIN (4575 2575) $PN BT75
J 0
(4585 2585);
DISPLAY 0.680851 (4585 2585);
PAINT MONO (4585 2585);
FORCEPROP 0 LASTPIN (4575 2625) $PN BT77
J 0
(4585 2635);
DISPLAY 0.680851 (4585 2635);
PAINT MONO (4585 2635);
FORCEPROP 0 LASTPIN (4575 2675) $PN BT79
J 0
(4585 2685);
DISPLAY 0.680851 (4585 2685);
PAINT MONO (4585 2685);
FORCEPROP 0 LASTPIN (4575 2725) $PN BT81
J 0
(4585 2735);
DISPLAY 0.680851 (4585 2735);
PAINT MONO (4585 2735);
FORCEPROP 0 LASTPIN (4575 2775) $PN BT83
J 0
(4585 2785);
DISPLAY 0.680851 (4585 2785);
PAINT MONO (4585 2785);
FORCEPROP 0 LASTPIN (4575 2825) $PN BT85
J 0
(4585 2835);
DISPLAY 0.680851 (4585 2835);
PAINT MONO (4585 2835);
FORCEPROP 0 LASTPIN (4575 2875) $PN BT87
J 0
(4585 2885);
DISPLAY 0.680851 (4585 2885);
PAINT MONO (4585 2885);
FORCEPROP 0 LASTPIN (4575 2925) $PN BT89
J 0
(4585 2935);
DISPLAY 0.680851 (4585 2935);
PAINT MONO (4585 2935);
FORCEPROP 0 LASTPIN (4575 2975) $PN BU33
J 0
(4585 2985);
DISPLAY 0.680851 (4585 2985);
PAINT MONO (4585 2985);
FORCEPROP 0 LASTPIN (4575 3025) $PN BU35
J 0
(4585 3035);
DISPLAY 0.680851 (4585 3035);
PAINT MONO (4585 3035);
FORCEPROP 0 LASTPIN (4575 3075) $PN BU37
J 0
(4585 3085);
DISPLAY 0.680851 (4585 3085);
PAINT MONO (4585 3085);
FORCEPROP 0 LASTPIN (4575 3125) $PN BU39
J 0
(4585 3135);
DISPLAY 0.680851 (4585 3135);
PAINT MONO (4585 3135);
FORCEPROP 0 LASTPIN (4575 3175) $PN BU41
J 0
(4585 3185);
DISPLAY 0.680851 (4585 3185);
PAINT MONO (4585 3185);
FORCEPROP 0 LASTPIN (4575 3225) $PN BU43
J 0
(4585 3235);
DISPLAY 0.680851 (4585 3235);
PAINT MONO (4585 3235);
FORCEPROP 0 LASTPIN (2175 -475) $PN BU45
J 2
(2165 -465);
DISPLAY 0.680851 (2165 -465);
PAINT MONO (2165 -465);
FORCEPROP 0 LASTPIN (2175 -425) $PN BU48
J 2
(2165 -415);
DISPLAY 0.680851 (2165 -415);
PAINT MONO (2165 -415);
FORCEPROP 0 LASTPIN (2175 -375) $PN BU50
J 2
(2165 -365);
DISPLAY 0.680851 (2165 -365);
PAINT MONO (2165 -365);
FORCEPROP 0 LASTPIN (2175 -325) $PN BU52
J 2
(2165 -315);
DISPLAY 0.680851 (2165 -315);
PAINT MONO (2165 -315);
FORCEPROP 0 LASTPIN (2175 -275) $PN BU54
J 2
(2165 -265);
DISPLAY 0.680851 (2165 -265);
PAINT MONO (2165 -265);
FORCEPROP 0 LASTPIN (2175 -225) $PN BU56
J 2
(2165 -215);
DISPLAY 0.680851 (2165 -215);
PAINT MONO (2165 -215);
FORCEPROP 0 LASTPIN (2175 -175) $PN BU58
J 2
(2165 -165);
DISPLAY 0.680851 (2165 -165);
PAINT MONO (2165 -165);
FORCEPROP 0 LASTPIN (2175 -125) $PN BU60
J 2
(2165 -115);
DISPLAY 0.680851 (2165 -115);
PAINT MONO (2165 -115);
FORCEPROP 0 LASTPIN (2175 -75) $PN BU62
J 2
(2165 -65);
DISPLAY 0.680851 (2165 -65);
PAINT MONO (2165 -65);
FORCEPROP 0 LASTPIN (2175 -25) $PN BU64
J 2
(2165 -15);
DISPLAY 0.680851 (2165 -15);
PAINT MONO (2165 -15);
FORCEPROP 0 LASTPIN (2175 25) $PN BU66
J 2
(2165 35);
DISPLAY 0.680851 (2165 35);
PAINT MONO (2165 35);
FORCEPROP 0 LASTPIN (2175 75) $PN BU68
J 2
(2165 85);
DISPLAY 0.680851 (2165 85);
PAINT MONO (2165 85);
FORCEPROP 0 LASTPIN (2175 125) $PN BU70
J 2
(2165 135);
DISPLAY 0.680851 (2165 135);
PAINT MONO (2165 135);
FORCEPROP 0 LASTPIN (2175 175) $PN BU72
J 2
(2165 185);
DISPLAY 0.680851 (2165 185);
PAINT MONO (2165 185);
FORCEPROP 0 LASTPIN (2175 225) $PN BU74
J 2
(2165 235);
DISPLAY 0.680851 (2165 235);
PAINT MONO (2165 235);
FORCEPROP 0 LASTPIN (2175 275) $PN BU76
J 2
(2165 285);
DISPLAY 0.680851 (2165 285);
PAINT MONO (2165 285);
FORCEPROP 0 LASTPIN (2175 325) $PN BU78
J 2
(2165 335);
DISPLAY 0.680851 (2165 335);
PAINT MONO (2165 335);
FORCEPROP 0 LASTPIN (2175 375) $PN BU80
J 2
(2165 385);
DISPLAY 0.680851 (2165 385);
PAINT MONO (2165 385);
FORCEPROP 0 LASTPIN (2175 425) $PN BU82
J 2
(2165 435);
DISPLAY 0.680851 (2165 435);
PAINT MONO (2165 435);
FORCEPROP 0 LASTPIN (2175 475) $PN BU84
J 2
(2165 485);
DISPLAY 0.680851 (2165 485);
PAINT MONO (2165 485);
FORCEPROP 0 LASTPIN (2175 525) $PN BU86
J 2
(2165 535);
DISPLAY 0.680851 (2165 535);
PAINT MONO (2165 535);
FORCEPROP 0 LASTPIN (2175 575) $PN BU88
J 2
(2165 585);
DISPLAY 0.680851 (2165 585);
PAINT MONO (2165 585);
FORCEPROP 0 LASTPIN (2175 625) $PN BU90
J 2
(2165 635);
DISPLAY 0.680851 (2165 635);
PAINT MONO (2165 635);
FORCEPROP 0 LASTPIN (2175 675) $PN BV32
J 2
(2165 685);
DISPLAY 0.680851 (2165 685);
PAINT MONO (2165 685);
FORCEPROP 0 LASTPIN (2175 725) $PN BV34
J 2
(2165 735);
DISPLAY 0.680851 (2165 735);
PAINT MONO (2165 735);
FORCEPROP 0 LASTPIN (2175 775) $PN BV36
J 2
(2165 785);
DISPLAY 0.680851 (2165 785);
PAINT MONO (2165 785);
FORCEPROP 0 LASTPIN (2175 825) $PN BV38
J 2
(2165 835);
DISPLAY 0.680851 (2165 835);
PAINT MONO (2165 835);
FORCEPROP 0 LASTPIN (2175 875) $PN BV40
J 2
(2165 885);
DISPLAY 0.680851 (2165 885);
PAINT MONO (2165 885);
FORCEPROP 0 LASTPIN (2175 925) $PN BV42
J 2
(2165 935);
DISPLAY 0.680851 (2165 935);
PAINT MONO (2165 935);
FORCEPROP 0 LASTPIN (2175 975) $PN BV44
J 2
(2165 985);
DISPLAY 0.680851 (2165 985);
PAINT MONO (2165 985);
FORCEPROP 0 LASTPIN (2175 1025) $PN BV47
J 2
(2165 1035);
DISPLAY 0.680851 (2165 1035);
PAINT MONO (2165 1035);
FORCEPROP 0 LASTPIN (2175 1075) $PN BV49
J 2
(2165 1085);
DISPLAY 0.680851 (2165 1085);
PAINT MONO (2165 1085);
FORCEPROP 0 LASTPIN (2175 1125) $PN BV51
J 2
(2165 1135);
DISPLAY 0.680851 (2165 1135);
PAINT MONO (2165 1135);
FORCEPROP 0 LASTPIN (2175 1175) $PN BV53
J 2
(2165 1185);
DISPLAY 0.680851 (2165 1185);
PAINT MONO (2165 1185);
FORCEPROP 0 LASTPIN (2175 1225) $PN BV55
J 2
(2165 1235);
DISPLAY 0.680851 (2165 1235);
PAINT MONO (2165 1235);
FORCEPROP 0 LASTPIN (2175 1275) $PN BV57
J 2
(2165 1285);
DISPLAY 0.680851 (2165 1285);
PAINT MONO (2165 1285);
FORCEPROP 0 LASTPIN (2175 1325) $PN BV59
J 2
(2165 1335);
DISPLAY 0.680851 (2165 1335);
PAINT MONO (2165 1335);
FORCEPROP 0 LASTPIN (2175 1375) $PN BV61
J 2
(2165 1385);
DISPLAY 0.680851 (2165 1385);
PAINT MONO (2165 1385);
FORCEPROP 0 LASTPIN (2175 1425) $PN BV63
J 2
(2165 1435);
DISPLAY 0.680851 (2165 1435);
PAINT MONO (2165 1435);
FORCEPROP 0 LASTPIN (2175 1475) $PN BV65
J 2
(2165 1485);
DISPLAY 0.680851 (2165 1485);
PAINT MONO (2165 1485);
FORCEPROP 0 LASTPIN (2175 1525) $PN BV67
J 2
(2165 1535);
DISPLAY 0.680851 (2165 1535);
PAINT MONO (2165 1535);
FORCEPROP 0 LASTPIN (2175 1575) $PN BV69
J 2
(2165 1585);
DISPLAY 0.680851 (2165 1585);
PAINT MONO (2165 1585);
FORCEPROP 0 LASTPIN (2175 1625) $PN BV71
J 2
(2165 1635);
DISPLAY 0.680851 (2165 1635);
PAINT MONO (2165 1635);
FORCEPROP 0 LASTPIN (2175 1675) $PN BV73
J 2
(2165 1685);
DISPLAY 0.680851 (2165 1685);
PAINT MONO (2165 1685);
FORCEPROP 0 LASTPIN (2175 1725) $PN BV75
J 2
(2165 1735);
DISPLAY 0.680851 (2165 1735);
PAINT MONO (2165 1735);
FORCEPROP 0 LASTPIN (2175 1775) $PN BV77
J 2
(2165 1785);
DISPLAY 0.680851 (2165 1785);
PAINT MONO (2165 1785);
FORCEPROP 0 LASTPIN (2175 1825) $PN BV79
J 2
(2165 1835);
DISPLAY 0.680851 (2165 1835);
PAINT MONO (2165 1835);
FORCEPROP 0 LASTPIN (2175 1875) $PN BV81
J 2
(2165 1885);
DISPLAY 0.680851 (2165 1885);
PAINT MONO (2165 1885);
FORCEPROP 0 LASTPIN (2175 1925) $PN BV83
J 2
(2165 1935);
DISPLAY 0.680851 (2165 1935);
PAINT MONO (2165 1935);
FORCEPROP 0 LASTPIN (2175 1975) $PN BV85
J 2
(2165 1985);
DISPLAY 0.680851 (2165 1985);
PAINT MONO (2165 1985);
FORCEPROP 0 LASTPIN (2175 2025) $PN BV87
J 2
(2165 2035);
DISPLAY 0.680851 (2165 2035);
PAINT MONO (2165 2035);
FORCEPROP 0 LASTPIN (2175 2075) $PN BV89
J 2
(2165 2085);
DISPLAY 0.680851 (2165 2085);
PAINT MONO (2165 2085);
FORCEPROP 0 LASTPIN (2175 2125) $PN BW33
J 2
(2165 2135);
DISPLAY 0.680851 (2165 2135);
PAINT MONO (2165 2135);
FORCEPROP 0 LASTPIN (2175 2175) $PN BW35
J 2
(2165 2185);
DISPLAY 0.680851 (2165 2185);
PAINT MONO (2165 2185);
FORCEPROP 0 LASTPIN (2175 2225) $PN BW37
J 2
(2165 2235);
DISPLAY 0.680851 (2165 2235);
PAINT MONO (2165 2235);
FORCEPROP 0 LASTPIN (2175 2275) $PN BW39
J 2
(2165 2285);
DISPLAY 0.680851 (2165 2285);
PAINT MONO (2165 2285);
FORCEPROP 0 LASTPIN (2175 2325) $PN BW41
J 2
(2165 2335);
DISPLAY 0.680851 (2165 2335);
PAINT MONO (2165 2335);
FORCEPROP 0 LASTPIN (2175 2375) $PN BW43
J 2
(2165 2385);
DISPLAY 0.680851 (2165 2385);
PAINT MONO (2165 2385);
FORCEPROP 0 LASTPIN (2175 2425) $PN BW45
J 2
(2165 2435);
DISPLAY 0.680851 (2165 2435);
PAINT MONO (2165 2435);
FORCEPROP 0 LASTPIN (2175 2475) $PN BW48
J 2
(2165 2485);
DISPLAY 0.680851 (2165 2485);
PAINT MONO (2165 2485);
FORCEPROP 0 LASTPIN (2175 2525) $PN BW50
J 2
(2165 2535);
DISPLAY 0.680851 (2165 2535);
PAINT MONO (2165 2535);
FORCEPROP 0 LASTPIN (2175 2575) $PN BW52
J 2
(2165 2585);
DISPLAY 0.680851 (2165 2585);
PAINT MONO (2165 2585);
FORCEPROP 0 LASTPIN (2175 2625) $PN BW54
J 2
(2165 2635);
DISPLAY 0.680851 (2165 2635);
PAINT MONO (2165 2635);
FORCEPROP 0 LASTPIN (2175 2675) $PN BW56
J 2
(2165 2685);
DISPLAY 0.680851 (2165 2685);
PAINT MONO (2165 2685);
FORCEPROP 0 LASTPIN (2175 2725) $PN BW58
J 2
(2165 2735);
DISPLAY 0.680851 (2165 2735);
PAINT MONO (2165 2735);
FORCEPROP 0 LASTPIN (2175 2775) $PN BW60
J 2
(2165 2785);
DISPLAY 0.680851 (2165 2785);
PAINT MONO (2165 2785);
FORCEPROP 0 LASTPIN (2175 2825) $PN BW62
J 2
(2165 2835);
DISPLAY 0.680851 (2165 2835);
PAINT MONO (2165 2835);
FORCEPROP 0 LASTPIN (2175 2875) $PN BW64
J 2
(2165 2885);
DISPLAY 0.680851 (2165 2885);
PAINT MONO (2165 2885);
FORCEPROP 0 LASTPIN (2175 2925) $PN BW66
J 2
(2165 2935);
DISPLAY 0.680851 (2165 2935);
PAINT MONO (2165 2935);
FORCEPROP 0 LASTPIN (2175 2975) $PN BW68
J 2
(2165 2985);
DISPLAY 0.680851 (2165 2985);
PAINT MONO (2165 2985);
FORCEPROP 0 LASTPIN (2175 3025) $PN BW70
J 2
(2165 3035);
DISPLAY 0.680851 (2165 3035);
PAINT MONO (2165 3035);
FORCEPROP 0 LASTPIN (2175 3075) $PN BW72
J 2
(2165 3085);
DISPLAY 0.680851 (2165 3085);
PAINT MONO (2165 3085);
FORCEPROP 0 LASTPIN (2175 3125) $PN BW74
J 2
(2165 3135);
DISPLAY 0.680851 (2165 3135);
PAINT MONO (2165 3135);
FORCEPROP 0 LASTPIN (2175 3175) $PN BW76
J 2
(2165 3185);
DISPLAY 0.680851 (2165 3185);
PAINT MONO (2165 3185);
FORCEPROP 0 LASTPIN (2175 3225) $PN BW78
J 2
(2165 3235);
DISPLAY 0.680851 (2165 3235);
PAINT MONO (2165 3235);
FORCEPROP 1 LAST CDS_LMAN_SYM_OUTLINE -1050,2000,1050,-2000
J 0
(3375 1375);
DISPLAY 0.468085 (3375 1375);
PAINT GREEN (3375 1375);
DISPLAY INVISIBLE (3375 1375);
FORCEPROP 1 LAST NEEDS_NO_SIZE TRUE
J 0
(3375 1375);
DISPLAY 0.723404 (3375 1375);
PAINT GREEN (3375 1375);
DISPLAY INVISIBLE (3375 1375);
FORCEPROP 2 LAST CDS_LIB pure_quanta
J 0
(3375 1375);
DISPLAY INVISIBLE (3375 1375);
FORCEPROP 2 LAST CDS_LOCATION U2
J 0
(2325 3700);
DISPLAY 1.021277 (2325 3700);
DISPLAY INVISIBLE (2325 3700);
FORCEPROP 0 LAST $SEC 27
J 0
(2325 3700);
DISPLAY 0.680851 (2325 3700);
PAINT MONO (2325 3700);
DISPLAY INVISIBLE (2325 3700);
FORCEPROP 2 LAST CDS_SEC 27
J 0
(2325 3700);
DISPLAY 1.021277 (2325 3700);
DISPLAY INVISIBLE (2325 3700);
FORCEPROP 1 LAST PATH I7
J 0
(3375 1375);
DISPLAY 0.723404 (3375 1375);
PAINT GREEN (3375 1375);
DISPLAY INVISIBLE (3375 1375);
FORCEADD QUANTA_TITLE_BLOCK_C..1
(5750 -1925);
FORCEPROP 0 LAST CDS_CON_LAST_MODIFIED Fri Aug 25 14:00:19 2023
J 0
(3865 -1910);
PAINT MONO (3865 -1910);
DISPLAY INVISIBLE (3865 -1910);
FORCEPROP 2 LAST CUSTOM_TXT_CDS <XR_PAGE_TITLE>
J 0
(-2140 3325);
DISPLAY 0.638298 (-2140 3325);
PAINT PINK (-2140 3325);
DISPLAY INVISIBLE (-2140 3325);
FORCEPROP 2 LAST CUSTOM_TXT_CDS <CON_PAGE_NUM> OF <CON_TOTAL_PAGES>
J 0
(5275 -1900);
DISPLAY 0.978723 (5275 -1900);
FORCEPROP 2 LAST CUSTOM_TXT_CDS <Q_NUMBER>
J 0
(4347 -1822);
DISPLAY 1.212766 (4347 -1822);
FORCEPROP 2 LAST CUSTOM_TXT_CDS <Q_REV>
J 0
(5566 -1822);
DISPLAY 1.212766 (5566 -1822);
FORCEPROP 2 LAST CUSTOM_TXT_CDS <CON_LAST_MODIFIED>
J 0
(3865 -1910);
DISPLAY 0.978723 (3865 -1910);
FORCEPROP 2 LAST CUSTOM_TXT_CDS <Q_PROJ>
J 0
(3368 -1823);
DISPLAY 1.212766 (3368 -1823);
FORCEPROP 1 LAST CUSTOM_TXT_CDS <NAME_2>
J 0
(2575 -1875);
FORCEPROP 1 LAST CUSTOM_TXT_CDS <NAME_1>
J 0
(2575 -1750);
FORCEPROP 1 LAST Q_TITLE SPR CPU0 POWER - VCCIN (24 OF 30)
J 0
(-3616 -1899);
DISPLAY 1.957447 (-3616 -1899);
PAINT GREEN (-3616 -1899);
FORCEPROP 1 LAST Q_DEPT 
J 1
(1987 -1876);
DISPLAY 1.957447 (1987 -1876);
PAINT GREEN (1987 -1876);
FORCEPROP 2 LAST PAGE_BORDER TRUE
J 0
(-2140 3325);
DISPLAY 0.638298 (-2140 3325);
PAINT PINK (-2140 3325);
DISPLAY INVISIBLE (-2140 3325);
FORCEPROP 1 LAST CDS_LMAN_SYM_OUTLINE -9475,6775,100,-125
J 0
(5750 -1925);
DISPLAY 0.468085 (5750 -1925);
PAINT GREEN (5750 -1925);
DISPLAY INVISIBLE (5750 -1925);
FORCEPROP 2 LAST CDS_LIB pure_quanta
J 0
(5750 -1925);
PAINT MONO (5750 -1925);
DISPLAY INVISIBLE (5750 -1925);
FORCEPROP 2 LAST CDS_XR_PAGE_TITLE CR-36 : @S9S_MB_2U_LIB.S9S_MB_2U(SCH_1):PAGE36
J 0
(-2140 3325);
DISPLAY 0.638298 (-2140 3325);
PAINT PINK (-2140 3325);
DISPLAY INVISIBLE (-2140 3325);
FORCEPROP 1 LAST COMMENT_BODY TRUE
J 0
(5762 -1938);
DISPLAY 0.978723 (5762 -1938);
PAINT GREEN (5762 -1938);
DISPLAY INVISIBLE (5762 -1938);
WIRE 16 -1 (1925 3400)(1925 3225);
WIRE 16 -1 (4825 3400)(4825 3225);
WIRE 16 -1 (450 3400)(450 3225);
WIRE 16 -1 (-2450 3400)(-2450 3225);
WIRE 16 -1 (2175 3225)(1925 3225);
WIRE 16 -1 (1925 3225)(1925 3175);
WIRE 16 -1 (2175 3175)(1925 3175);
WIRE 16 -1 (1925 3175)(1925 3125);
WIRE 16 -1 (2175 3125)(1925 3125);
WIRE 16 -1 (1925 3125)(1925 3075);
WIRE 16 -1 (2175 3075)(1925 3075);
WIRE 16 -1 (1925 3075)(1925 3025);
WIRE 16 -1 (2175 3025)(1925 3025);
WIRE 16 -1 (1925 3025)(1925 2975);
WIRE 16 -1 (2175 2975)(1925 2975);
WIRE 16 -1 (1925 2975)(1925 2925);
WIRE 16 -1 (2175 2925)(1925 2925);
WIRE 16 -1 (1925 2925)(1925 2875);
WIRE 16 -1 (2175 2875)(1925 2875);
WIRE 16 -1 (1925 2875)(1925 2825);
WIRE 16 -1 (2175 2825)(1925 2825);
WIRE 16 -1 (1925 2825)(1925 2775);
WIRE 16 -1 (2175 2775)(1925 2775);
WIRE 16 -1 (1925 2775)(1925 2725);
WIRE 16 -1 (2175 2725)(1925 2725);
WIRE 16 -1 (1925 2725)(1925 2675);
WIRE 16 -1 (2175 2675)(1925 2675);
WIRE 16 -1 (1925 2675)(1925 2625);
WIRE 16 -1 (2175 2625)(1925 2625);
WIRE 16 -1 (1925 2625)(1925 2575);
WIRE 16 -1 (2175 2575)(1925 2575);
WIRE 16 -1 (1925 2575)(1925 2525);
WIRE 16 -1 (1925 2525)(2175 2525);
WIRE 16 -1 (1925 2525)(1925 2475);
WIRE 16 -1 (1925 2475)(2175 2475);
WIRE 16 -1 (1925 2475)(1925 2425);
WIRE 16 -1 (1925 2425)(2175 2425);
WIRE 16 -1 (1925 2425)(1925 2375);
WIRE 16 -1 (1925 2375)(2175 2375);
WIRE 16 -1 (1925 2375)(1925 2325);
WIRE 16 -1 (1925 2325)(2175 2325);
WIRE 16 -1 (1925 2325)(1925 2275);
WIRE 16 -1 (1925 2275)(2175 2275);
WIRE 16 -1 (1925 2275)(1925 2225);
WIRE 16 -1 (1925 2225)(2175 2225);
WIRE 16 -1 (1925 2225)(1925 2175);
WIRE 16 -1 (1925 2175)(2175 2175);
WIRE 16 -1 (1925 2175)(1925 2125);
WIRE 16 -1 (1925 2125)(2175 2125);
WIRE 16 -1 (1925 2125)(1925 2075);
WIRE 16 -1 (1925 2075)(2175 2075);
WIRE 16 -1 (1925 2075)(1925 2025);
WIRE 16 -1 (1925 2025)(2175 2025);
WIRE 16 -1 (1925 2025)(1925 1975);
WIRE 16 -1 (1925 1975)(2175 1975);
WIRE 16 -1 (1925 1975)(1925 1925);
WIRE 16 -1 (1925 1925)(2175 1925);
WIRE 16 -1 (1925 1925)(1925 1875);
WIRE 16 -1 (1925 1875)(2175 1875);
WIRE 16 -1 (1925 1875)(1925 1825);
WIRE 16 -1 (1925 1825)(2175 1825);
WIRE 16 -1 (1925 1825)(1925 1775);
WIRE 16 -1 (1925 1775)(2175 1775);
WIRE 16 -1 (1925 1775)(1925 1725);
WIRE 16 -1 (1925 1725)(2175 1725);
WIRE 16 -1 (1925 1725)(1925 1675);
WIRE 16 -1 (1925 1675)(2175 1675);
WIRE 16 -1 (1925 1675)(1925 1625);
WIRE 16 -1 (1925 1625)(2175 1625);
WIRE 16 -1 (1925 1625)(1925 1575);
WIRE 16 -1 (1925 1575)(2175 1575);
WIRE 16 -1 (1925 1575)(1925 1525);
WIRE 16 -1 (1925 1525)(2175 1525);
WIRE 16 -1 (1925 1525)(1925 1475);
WIRE 16 -1 (1925 1475)(2175 1475);
WIRE 16 -1 (1925 1475)(1925 1425);
WIRE 16 -1 (1925 1425)(2175 1425);
WIRE 16 -1 (1925 1425)(1925 1375);
WIRE 16 -1 (1925 1375)(2175 1375);
WIRE 16 -1 (1925 1375)(1925 1325);
WIRE 16 -1 (1925 1325)(2175 1325);
WIRE 16 -1 (1925 1325)(1925 1275);
WIRE 16 -1 (1925 1275)(2175 1275);
WIRE 16 -1 (1925 1275)(1925 1225);
WIRE 16 -1 (1925 1225)(2175 1225);
WIRE 16 -1 (1925 1225)(1925 1175);
WIRE 16 -1 (1925 1175)(2175 1175);
WIRE 16 -1 (1925 1175)(1925 1125);
WIRE 16 -1 (1925 1125)(2175 1125);
WIRE 16 -1 (1925 1125)(1925 1075);
WIRE 16 -1 (1925 1075)(2175 1075);
WIRE 16 -1 (1925 1075)(1925 1025);
WIRE 16 -1 (1925 1025)(2175 1025);
WIRE 16 -1 (1925 1025)(1925 975);
WIRE 16 -1 (1925 975)(2175 975);
WIRE 16 -1 (1925 975)(1925 925);
WIRE 16 -1 (1925 925)(2175 925);
WIRE 16 -1 (1925 925)(1925 875);
WIRE 16 -1 (1925 875)(2175 875);
WIRE 16 -1 (1925 875)(1925 825);
WIRE 16 -1 (1925 825)(2175 825);
WIRE 16 -1 (1925 825)(1925 775);
WIRE 16 -1 (1925 775)(2175 775);
WIRE 16 -1 (1925 775)(1925 725);
WIRE 16 -1 (1925 725)(2175 725);
WIRE 16 -1 (1925 725)(1925 675);
WIRE 16 -1 (1925 675)(2175 675);
WIRE 16 -1 (1925 675)(1925 625);
WIRE 16 -1 (1925 625)(2175 625);
WIRE 16 -1 (1925 625)(1925 575);
WIRE 16 -1 (1925 575)(2175 575);
WIRE 16 -1 (1925 575)(1925 525);
WIRE 16 -1 (1925 525)(2175 525);
WIRE 16 -1 (1925 525)(1925 475);
WIRE 16 -1 (1925 475)(2175 475);
WIRE 16 -1 (1925 475)(1925 425);
WIRE 16 -1 (2175 425)(1925 425);
WIRE 16 -1 (1925 425)(1925 375);
WIRE 16 -1 (2175 375)(1925 375);
WIRE 16 -1 (1925 375)(1925 325);
WIRE 16 -1 (2175 325)(1925 325);
WIRE 16 -1 (1925 325)(1925 275);
WIRE 16 -1 (2175 275)(1925 275);
WIRE 16 -1 (1925 275)(1925 225);
WIRE 16 -1 (2175 225)(1925 225);
WIRE 16 -1 (1925 225)(1925 175);
WIRE 16 -1 (2175 175)(1925 175);
WIRE 16 -1 (1925 175)(1925 125);
WIRE 16 -1 (2175 125)(1925 125);
WIRE 16 -1 (1925 125)(1925 75);
WIRE 16 -1 (2175 75)(1925 75);
WIRE 16 -1 (1925 75)(1925 25);
WIRE 16 -1 (2175 25)(1925 25);
WIRE 16 -1 (2175 -25)(1925 -25);
WIRE 16 -1 (1925 25)(1925 -25);
WIRE 16 -1 (1925 -25)(1925 -75);
WIRE 16 -1 (2175 -75)(1925 -75);
WIRE 16 -1 (1925 -75)(1925 -125);
WIRE 16 -1 (2175 -125)(1925 -125);
WIRE 16 -1 (1925 -175)(1925 -125);
WIRE 16 -1 (2175 -175)(1925 -175);
WIRE 16 -1 (1925 -175)(1925 -225);
WIRE 16 -1 (2175 -225)(1925 -225);
WIRE 16 -1 (1925 -275)(1925 -225);
WIRE 16 -1 (2175 -275)(1925 -275);
WIRE 16 -1 (1925 -275)(1925 -325);
WIRE 16 -1 (2175 -325)(1925 -325);
WIRE 16 -1 (1925 -375)(1925 -325);
WIRE 16 -1 (2175 -375)(1925 -375);
WIRE 16 -1 (1925 -375)(1925 -425);
WIRE 16 -1 (2175 -425)(1925 -425);
WIRE 16 -1 (1925 -475)(1925 -425);
WIRE 16 -1 (2175 -475)(1925 -475);
WIRE 16 -1 (4825 3225)(4575 3225);
WIRE 16 -1 (4825 3175)(4575 3175);
WIRE 16 -1 (4825 3225)(4825 3175);
WIRE 16 -1 (4825 3125)(4575 3125);
WIRE 16 -1 (4825 3175)(4825 3125);
WIRE 16 -1 (4825 3075)(4575 3075);
WIRE 16 -1 (4825 3125)(4825 3075);
WIRE 16 -1 (4825 3025)(4575 3025);
WIRE 16 -1 (4825 3075)(4825 3025);
WIRE 16 -1 (4825 2975)(4575 2975);
WIRE 16 -1 (4825 3025)(4825 2975);
WIRE 16 -1 (4825 2925)(4575 2925);
WIRE 16 -1 (4825 2975)(4825 2925);
WIRE 16 -1 (4825 2875)(4575 2875);
WIRE 16 -1 (4825 2925)(4825 2875);
WIRE 16 -1 (4825 2825)(4575 2825);
WIRE 16 -1 (4825 2875)(4825 2825);
WIRE 16 -1 (4825 2775)(4575 2775);
WIRE 16 -1 (4825 2825)(4825 2775);
WIRE 16 -1 (4825 2725)(4575 2725);
WIRE 16 -1 (4825 2775)(4825 2725);
WIRE 16 -1 (4825 2675)(4575 2675);
WIRE 16 -1 (4825 2725)(4825 2675);
WIRE 16 -1 (4825 2625)(4575 2625);
WIRE 16 -1 (4825 2675)(4825 2625);
WIRE 16 -1 (4825 2575)(4575 2575);
WIRE 16 -1 (4825 2625)(4825 2575);
WIRE 16 -1 (4575 2525)(4825 2525);
WIRE 16 -1 (4825 2575)(4825 2525);
WIRE 16 -1 (4575 2475)(4825 2475);
WIRE 16 -1 (4825 2525)(4825 2475);
WIRE 16 -1 (4575 2425)(4825 2425);
WIRE 16 -1 (4825 2475)(4825 2425);
WIRE 16 -1 (4575 2375)(4825 2375);
WIRE 16 -1 (4825 2425)(4825 2375);
WIRE 16 -1 (4575 2325)(4825 2325);
WIRE 16 -1 (4825 2375)(4825 2325);
WIRE 16 -1 (4575 2275)(4825 2275);
WIRE 16 -1 (4825 2325)(4825 2275);
WIRE 16 -1 (4575 2225)(4825 2225);
WIRE 16 -1 (4825 2275)(4825 2225);
WIRE 16 -1 (4575 2175)(4825 2175);
WIRE 16 -1 (4825 2225)(4825 2175);
WIRE 16 -1 (4575 2125)(4825 2125);
WIRE 16 -1 (4825 2175)(4825 2125);
WIRE 16 -1 (4575 2075)(4825 2075);
WIRE 16 -1 (4825 2125)(4825 2075);
WIRE 16 -1 (4575 2025)(4825 2025);
WIRE 16 -1 (4825 2075)(4825 2025);
WIRE 16 -1 (4575 1975)(4825 1975);
WIRE 16 -1 (4825 2025)(4825 1975);
WIRE 16 -1 (4575 1925)(4825 1925);
WIRE 16 -1 (4825 1975)(4825 1925);
WIRE 16 -1 (4575 1875)(4825 1875);
WIRE 16 -1 (4825 1925)(4825 1875);
WIRE 16 -1 (4575 1825)(4825 1825);
WIRE 16 -1 (4825 1875)(4825 1825);
WIRE 16 -1 (4575 1775)(4825 1775);
WIRE 16 -1 (4825 1825)(4825 1775);
WIRE 16 -1 (4575 1725)(4825 1725);
WIRE 16 -1 (4825 1775)(4825 1725);
WIRE 16 -1 (4575 1675)(4825 1675);
WIRE 16 -1 (4825 1725)(4825 1675);
WIRE 16 -1 (4575 1625)(4825 1625);
WIRE 16 -1 (4825 1675)(4825 1625);
WIRE 16 -1 (4575 1575)(4825 1575);
WIRE 16 -1 (4825 1625)(4825 1575);
WIRE 16 -1 (4825 1525)(4575 1525);
WIRE 16 -1 (4825 1575)(4825 1525);
WIRE 16 -1 (4575 1475)(4825 1475);
WIRE 16 -1 (4825 1525)(4825 1475);
WIRE 16 -1 (4575 1425)(4825 1425);
WIRE 16 -1 (4825 1475)(4825 1425);
WIRE 16 -1 (4575 1375)(4825 1375);
WIRE 16 -1 (4825 1425)(4825 1375);
WIRE 16 -1 (4575 1325)(4825 1325);
WIRE 16 -1 (4825 1375)(4825 1325);
WIRE 16 -1 (4575 1275)(4825 1275);
WIRE 16 -1 (4825 1325)(4825 1275);
WIRE 16 -1 (4575 1225)(4825 1225);
WIRE 16 -1 (4825 1275)(4825 1225);
WIRE 16 -1 (4575 1175)(4825 1175);
WIRE 16 -1 (4825 1225)(4825 1175);
WIRE 16 -1 (4575 1125)(4825 1125);
WIRE 16 -1 (4825 1175)(4825 1125);
WIRE 16 -1 (4575 1075)(4825 1075);
WIRE 16 -1 (4825 1125)(4825 1075);
WIRE 16 -1 (4575 1025)(4825 1025);
WIRE 16 -1 (4825 1075)(4825 1025);
WIRE 16 -1 (4575 975)(4825 975);
WIRE 16 -1 (4825 1025)(4825 975);
WIRE 16 -1 (4575 925)(4825 925);
WIRE 16 -1 (4825 975)(4825 925);
WIRE 16 -1 (4575 875)(4825 875);
WIRE 16 -1 (4825 925)(4825 875);
WIRE 16 -1 (4575 825)(4825 825);
WIRE 16 -1 (4825 875)(4825 825);
WIRE 16 -1 (4575 775)(4825 775);
WIRE 16 -1 (4825 825)(4825 775);
WIRE 16 -1 (4575 725)(4825 725);
WIRE 16 -1 (4825 775)(4825 725);
WIRE 16 -1 (4575 675)(4825 675);
WIRE 16 -1 (4825 725)(4825 675);
WIRE 16 -1 (4575 625)(4825 625);
WIRE 16 -1 (4825 675)(4825 625);
WIRE 16 -1 (4575 575)(4825 575);
WIRE 16 -1 (4825 625)(4825 575);
WIRE 16 -1 (4575 525)(4825 525);
WIRE 16 -1 (4825 575)(4825 525);
WIRE 16 -1 (4825 475)(4575 475);
WIRE 16 -1 (4825 525)(4825 475);
WIRE 16 -1 (4825 425)(4575 425);
WIRE 16 -1 (4825 475)(4825 425);
WIRE 16 -1 (4825 375)(4575 375);
WIRE 16 -1 (4825 425)(4825 375);
WIRE 16 -1 (4825 325)(4575 325);
WIRE 16 -1 (4825 375)(4825 325);
WIRE 16 -1 (4825 275)(4575 275);
WIRE 16 -1 (4825 325)(4825 275);
WIRE 16 -1 (4825 225)(4575 225);
WIRE 16 -1 (4825 275)(4825 225);
WIRE 16 -1 (4825 175)(4575 175);
WIRE 16 -1 (4825 225)(4825 175);
WIRE 16 -1 (4825 125)(4575 125);
WIRE 16 -1 (4825 175)(4825 125);
WIRE 16 -1 (4825 75)(4575 75);
WIRE 16 -1 (4825 125)(4825 75);
WIRE 16 -1 (4825 25)(4575 25);
WIRE 16 -1 (4825 75)(4825 25);
WIRE 16 -1 (4825 -25)(4575 -25);
WIRE 16 -1 (4825 25)(4825 -25);
WIRE 16 -1 (4825 -75)(4575 -75);
WIRE 16 -1 (4825 -25)(4825 -75);
WIRE 16 -1 (4825 -125)(4575 -125);
WIRE 16 -1 (4825 -75)(4825 -125);
WIRE 16 -1 (4575 -175)(4825 -175);
WIRE 16 -1 (4825 -175)(4825 -125);
WIRE 16 -1 (4825 -225)(4575 -225);
WIRE 16 -1 (4825 -175)(4825 -225);
WIRE 16 -1 (4825 -275)(4575 -275);
WIRE 16 -1 (4825 -225)(4825 -275);
WIRE 16 -1 (4825 -325)(4575 -325);
WIRE 16 -1 (4825 -275)(4825 -325);
WIRE 16 -1 (4825 -375)(4575 -375);
WIRE 16 -1 (4825 -325)(4825 -375);
WIRE 16 -1 (4575 -425)(4825 -425);
WIRE 16 -1 (4825 -425)(4825 -375);
WIRE 16 -1 (4825 -475)(4825 -425);
WIRE 16 -1 (4575 -475)(4825 -475);
WIRE 16 -1 (-2200 3225)(-2450 3225);
WIRE 16 -1 (-2450 3225)(-2450 3175);
WIRE 16 -1 (-2200 3175)(-2450 3175);
WIRE 16 -1 (-2450 3175)(-2450 3125);
WIRE 16 -1 (-2200 3125)(-2450 3125);
WIRE 16 -1 (-2450 3125)(-2450 3075);
WIRE 16 -1 (-2200 3075)(-2450 3075);
WIRE 16 -1 (-2200 3025)(-2450 3025);
WIRE 16 -1 (-2450 3075)(-2450 3025);
WIRE 16 -1 (-2450 3025)(-2450 2975);
WIRE 16 -1 (-2200 2975)(-2450 2975);
WIRE 16 -1 (-2450 2975)(-2450 2925);
WIRE 16 -1 (-2200 2925)(-2450 2925);
WIRE 16 -1 (-2450 2925)(-2450 2875);
WIRE 16 -1 (-2200 2875)(-2450 2875);
WIRE 16 -1 (-2450 2875)(-2450 2825);
WIRE 16 -1 (-2200 2825)(-2450 2825);
WIRE 16 -1 (-2450 2825)(-2450 2775);
WIRE 16 -1 (-2200 2775)(-2450 2775);
WIRE 16 -1 (-2450 2775)(-2450 2725);
WIRE 16 -1 (-2200 2725)(-2450 2725);
WIRE 16 -1 (-2450 2725)(-2450 2675);
WIRE 16 -1 (-2200 2675)(-2450 2675);
WIRE 16 -1 (-2450 2675)(-2450 2625);
WIRE 16 -1 (-2200 2625)(-2450 2625);
WIRE 16 -1 (-2450 2625)(-2450 2575);
WIRE 16 -1 (-2200 2575)(-2450 2575);
WIRE 16 -1 (-2450 2525)(-2200 2525);
WIRE 16 -1 (-2450 2575)(-2450 2525);
WIRE 16 -1 (-2450 2525)(-2450 2475);
WIRE 16 -1 (-2450 2475)(-2200 2475);
WIRE 16 -1 (-2450 2475)(-2450 2425);
WIRE 16 -1 (-2450 2425)(-2200 2425);
WIRE 16 -1 (-2450 2425)(-2450 2375);
WIRE 16 -1 (-2450 2375)(-2200 2375);
WIRE 16 -1 (-2450 2375)(-2450 2325);
WIRE 16 -1 (-2450 2325)(-2200 2325);
WIRE 16 -1 (-2450 2325)(-2450 2275);
WIRE 16 -1 (-2450 2275)(-2200 2275);
WIRE 16 -1 (-2450 2275)(-2450 2225);
WIRE 16 -1 (-2450 2225)(-2200 2225);
WIRE 16 -1 (-2450 2225)(-2450 2175);
WIRE 16 -1 (-2450 2175)(-2200 2175);
WIRE 16 -1 (-2450 2175)(-2450 2125);
WIRE 16 -1 (-2450 2125)(-2200 2125);
WIRE 16 -1 (-2450 2125)(-2450 2075);
WIRE 16 -1 (-2450 2075)(-2200 2075);
WIRE 16 -1 (-2450 2025)(-2200 2025);
WIRE 16 -1 (-2450 2075)(-2450 2025);
WIRE 16 -1 (-2450 2025)(-2450 1975);
WIRE 16 -1 (-2450 1975)(-2200 1975);
WIRE 16 -1 (-2450 1975)(-2450 1925);
WIRE 16 -1 (-2450 1925)(-2200 1925);
WIRE 16 -1 (-2450 1925)(-2450 1875);
WIRE 16 -1 (-2450 1875)(-2200 1875);
WIRE 16 -1 (-2450 1875)(-2450 1825);
WIRE 16 -1 (-2450 1825)(-2200 1825);
WIRE 16 -1 (-2450 1825)(-2450 1775);
WIRE 16 -1 (-2450 1775)(-2200 1775);
WIRE 16 -1 (-2450 1775)(-2450 1725);
WIRE 16 -1 (-2450 1725)(-2200 1725);
WIRE 16 -1 (-2450 1725)(-2450 1675);
WIRE 16 -1 (-2450 1675)(-2200 1675);
WIRE 16 -1 (-2450 1675)(-2450 1625);
WIRE 16 -1 (-2450 1625)(-2200 1625);
WIRE 16 -1 (-2450 1625)(-2450 1575);
WIRE 16 -1 (-2450 1575)(-2200 1575);
WIRE 16 -1 (-2450 1525)(-2200 1525);
WIRE 16 -1 (-2450 1575)(-2450 1525);
WIRE 16 -1 (-2450 1525)(-2450 1475);
WIRE 16 -1 (-2450 1475)(-2200 1475);
WIRE 16 -1 (-2450 1475)(-2450 1425);
WIRE 16 -1 (-2450 1425)(-2200 1425);
WIRE 16 -1 (-2450 1425)(-2450 1375);
WIRE 16 -1 (-2450 1375)(-2200 1375);
WIRE 16 -1 (-2450 1375)(-2450 1325);
WIRE 16 -1 (-2450 1325)(-2200 1325);
WIRE 16 -1 (-2450 1325)(-2450 1275);
WIRE 16 -1 (-2450 1275)(-2200 1275);
WIRE 16 -1 (-2450 1275)(-2450 1225);
WIRE 16 -1 (-2450 1225)(-2200 1225);
WIRE 16 -1 (-2450 1225)(-2450 1175);
WIRE 16 -1 (-2450 1175)(-2200 1175);
WIRE 16 -1 (-2450 1175)(-2450 1125);
WIRE 16 -1 (-2450 1125)(-2200 1125);
WIRE 16 -1 (-2450 1125)(-2450 1075);
WIRE 16 -1 (-2450 1075)(-2200 1075);
WIRE 16 -1 (-2450 1075)(-2450 1025);
WIRE 16 -1 (-2450 1025)(-2200 1025);
WIRE 16 -1 (-2450 975)(-2200 975);
WIRE 16 -1 (-2450 1025)(-2450 975);
WIRE 16 -1 (-2450 975)(-2450 925);
WIRE 16 -1 (-2450 925)(-2200 925);
WIRE 16 -1 (-2450 925)(-2450 875);
WIRE 16 -1 (-2450 875)(-2200 875);
WIRE 16 -1 (-2450 875)(-2450 825);
WIRE 16 -1 (-2450 825)(-2200 825);
WIRE 16 -1 (-2450 825)(-2450 775);
WIRE 16 -1 (-2450 775)(-2200 775);
WIRE 16 -1 (-2450 775)(-2450 725);
WIRE 16 -1 (-2450 725)(-2200 725);
WIRE 16 -1 (-2450 725)(-2450 675);
WIRE 16 -1 (-2450 675)(-2200 675);
WIRE 16 -1 (-2450 675)(-2450 625);
WIRE 16 -1 (-2450 625)(-2200 625);
WIRE 16 -1 (-2450 625)(-2450 575);
WIRE 16 -1 (-2450 575)(-2200 575);
WIRE 16 -1 (-2450 575)(-2450 525);
WIRE 16 -1 (-2450 525)(-2200 525);
WIRE 16 -1 (-2450 475)(-2200 475);
WIRE 16 -1 (-2450 525)(-2450 475);
WIRE 16 -1 (-2450 475)(-2450 425);
WIRE 16 -1 (-2200 425)(-2450 425);
WIRE 16 -1 (-2450 425)(-2450 375);
WIRE 16 -1 (-2200 375)(-2450 375);
WIRE 16 -1 (-2450 375)(-2450 325);
WIRE 16 -1 (-2200 325)(-2450 325);
WIRE 16 -1 (-2450 325)(-2450 275);
WIRE 16 -1 (-2200 275)(-2450 275);
WIRE 16 -1 (-2450 275)(-2450 225);
WIRE 16 -1 (-2200 225)(-2450 225);
WIRE 16 -1 (-2450 225)(-2450 175);
WIRE 16 -1 (-2200 175)(-2450 175);
WIRE 16 -1 (-2450 175)(-2450 125);
WIRE 16 -1 (-2200 125)(-2450 125);
WIRE 16 -1 (-2450 125)(-2450 75);
WIRE 16 -1 (-2200 75)(-2450 75);
WIRE 16 -1 (-2450 75)(-2450 25);
WIRE 16 -1 (-2200 25)(-2450 25);
WIRE 16 -1 (-2200 -25)(-2450 -25);
WIRE 16 -1 (-2450 25)(-2450 -25);
WIRE 16 -1 (-2450 -25)(-2450 -75);
WIRE 16 -1 (-2200 -75)(-2450 -75);
WIRE 16 -1 (-2450 -75)(-2450 -125);
WIRE 16 -1 (-2200 -125)(-2450 -125);
WIRE 16 -1 (-2450 -175)(-2450 -125);
WIRE 16 -1 (-2200 -175)(-2450 -175);
WIRE 16 -1 (-2450 -175)(-2450 -225);
WIRE 16 -1 (-2200 -225)(-2450 -225);
WIRE 16 -1 (-2450 -275)(-2450 -225);
WIRE 16 -1 (-2200 -275)(-2450 -275);
WIRE 16 -1 (-2450 -275)(-2450 -325);
WIRE 16 -1 (-2200 -325)(-2450 -325);
WIRE 16 -1 (-2450 -375)(-2450 -325);
WIRE 16 -1 (-2200 -375)(-2450 -375);
WIRE 16 -1 (-2450 -375)(-2450 -425);
WIRE 16 -1 (-2200 -425)(-2450 -425);
WIRE 16 -1 (-2450 -475)(-2450 -425);
WIRE 16 -1 (-2200 -475)(-2450 -475);
WIRE 16 -1 (450 3225)(200 3225);
WIRE 16 -1 (450 3175)(200 3175);
WIRE 16 -1 (450 3225)(450 3175);
WIRE 16 -1 (450 3125)(200 3125);
WIRE 16 -1 (450 3175)(450 3125);
WIRE 16 -1 (450 3075)(200 3075);
WIRE 16 -1 (450 3125)(450 3075);
WIRE 16 -1 (450 3025)(200 3025);
WIRE 16 -1 (450 3075)(450 3025);
WIRE 16 -1 (450 2975)(200 2975);
WIRE 16 -1 (450 3025)(450 2975);
WIRE 16 -1 (450 2925)(200 2925);
WIRE 16 -1 (450 2975)(450 2925);
WIRE 16 -1 (450 2875)(200 2875);
WIRE 16 -1 (450 2925)(450 2875);
WIRE 16 -1 (450 2825)(200 2825);
WIRE 16 -1 (450 2875)(450 2825);
WIRE 16 -1 (450 2775)(200 2775);
WIRE 16 -1 (450 2825)(450 2775);
WIRE 16 -1 (450 2725)(200 2725);
WIRE 16 -1 (450 2775)(450 2725);
WIRE 16 -1 (450 2675)(200 2675);
WIRE 16 -1 (450 2725)(450 2675);
WIRE 16 -1 (450 2625)(200 2625);
WIRE 16 -1 (450 2675)(450 2625);
WIRE 16 -1 (450 2575)(200 2575);
WIRE 16 -1 (450 2625)(450 2575);
WIRE 16 -1 (200 2525)(450 2525);
WIRE 16 -1 (450 2575)(450 2525);
WIRE 16 -1 (200 2475)(450 2475);
WIRE 16 -1 (450 2525)(450 2475);
WIRE 16 -1 (200 2425)(450 2425);
WIRE 16 -1 (450 2475)(450 2425);
WIRE 16 -1 (200 2375)(450 2375);
WIRE 16 -1 (450 2425)(450 2375);
WIRE 16 -1 (200 2325)(450 2325);
WIRE 16 -1 (450 2375)(450 2325);
WIRE 16 -1 (200 2275)(450 2275);
WIRE 16 -1 (450 2325)(450 2275);
WIRE 16 -1 (200 2225)(450 2225);
WIRE 16 -1 (450 2275)(450 2225);
WIRE 16 -1 (200 2175)(450 2175);
WIRE 16 -1 (450 2225)(450 2175);
WIRE 16 -1 (200 2125)(450 2125);
WIRE 16 -1 (450 2175)(450 2125);
WIRE 16 -1 (200 2075)(450 2075);
WIRE 16 -1 (450 2125)(450 2075);
WIRE 16 -1 (200 2025)(450 2025);
WIRE 16 -1 (450 2075)(450 2025);
WIRE 16 -1 (200 1975)(450 1975);
WIRE 16 -1 (450 2025)(450 1975);
WIRE 16 -1 (200 1925)(450 1925);
WIRE 16 -1 (450 1975)(450 1925);
WIRE 16 -1 (200 1875)(450 1875);
WIRE 16 -1 (450 1925)(450 1875);
WIRE 16 -1 (200 1825)(450 1825);
WIRE 16 -1 (450 1875)(450 1825);
WIRE 16 -1 (200 1775)(450 1775);
WIRE 16 -1 (450 1825)(450 1775);
WIRE 16 -1 (200 1725)(450 1725);
WIRE 16 -1 (450 1775)(450 1725);
WIRE 16 -1 (200 1675)(450 1675);
WIRE 16 -1 (450 1725)(450 1675);
WIRE 16 -1 (200 1625)(450 1625);
WIRE 16 -1 (450 1675)(450 1625);
WIRE 16 -1 (200 1575)(450 1575);
WIRE 16 -1 (450 1625)(450 1575);
WIRE 16 -1 (450 1525)(200 1525);
WIRE 16 -1 (450 1575)(450 1525);
WIRE 16 -1 (200 1475)(450 1475);
WIRE 16 -1 (450 1525)(450 1475);
WIRE 16 -1 (200 1425)(450 1425);
WIRE 16 -1 (450 1475)(450 1425);
WIRE 16 -1 (200 1375)(450 1375);
WIRE 16 -1 (450 1425)(450 1375);
WIRE 16 -1 (200 1325)(450 1325);
WIRE 16 -1 (450 1375)(450 1325);
WIRE 16 -1 (200 1275)(450 1275);
WIRE 16 -1 (450 1325)(450 1275);
WIRE 16 -1 (200 1225)(450 1225);
WIRE 16 -1 (450 1275)(450 1225);
WIRE 16 -1 (200 1175)(450 1175);
WIRE 16 -1 (450 1225)(450 1175);
WIRE 16 -1 (200 1125)(450 1125);
WIRE 16 -1 (450 1175)(450 1125);
WIRE 16 -1 (200 1075)(450 1075);
WIRE 16 -1 (450 1125)(450 1075);
WIRE 16 -1 (200 1025)(450 1025);
WIRE 16 -1 (450 1075)(450 1025);
WIRE 16 -1 (200 975)(450 975);
WIRE 16 -1 (450 1025)(450 975);
WIRE 16 -1 (200 925)(450 925);
WIRE 16 -1 (450 975)(450 925);
WIRE 16 -1 (200 875)(450 875);
WIRE 16 -1 (450 925)(450 875);
WIRE 16 -1 (200 825)(450 825);
WIRE 16 -1 (450 875)(450 825);
WIRE 16 -1 (200 775)(450 775);
WIRE 16 -1 (450 825)(450 775);
WIRE 16 -1 (200 725)(450 725);
WIRE 16 -1 (450 775)(450 725);
WIRE 16 -1 (200 675)(450 675);
WIRE 16 -1 (450 725)(450 675);
WIRE 16 -1 (200 625)(450 625);
WIRE 16 -1 (450 675)(450 625);
WIRE 16 -1 (200 575)(450 575);
WIRE 16 -1 (450 625)(450 575);
WIRE 16 -1 (200 525)(450 525);
WIRE 16 -1 (450 575)(450 525);
WIRE 16 -1 (450 475)(200 475);
WIRE 16 -1 (450 525)(450 475);
WIRE 16 -1 (450 425)(200 425);
WIRE 16 -1 (450 475)(450 425);
WIRE 16 -1 (450 375)(200 375);
WIRE 16 -1 (450 425)(450 375);
WIRE 16 -1 (450 325)(200 325);
WIRE 16 -1 (450 375)(450 325);
WIRE 16 -1 (450 275)(200 275);
WIRE 16 -1 (450 325)(450 275);
WIRE 16 -1 (450 225)(200 225);
WIRE 16 -1 (450 275)(450 225);
WIRE 16 -1 (450 175)(200 175);
WIRE 16 -1 (450 225)(450 175);
WIRE 16 -1 (450 125)(200 125);
WIRE 16 -1 (450 175)(450 125);
WIRE 16 -1 (450 75)(200 75);
WIRE 16 -1 (450 125)(450 75);
WIRE 16 -1 (450 25)(200 25);
WIRE 16 -1 (450 75)(450 25);
WIRE 16 -1 (450 -25)(200 -25);
WIRE 16 -1 (450 25)(450 -25);
WIRE 16 -1 (450 -75)(200 -75);
WIRE 16 -1 (450 -25)(450 -75);
WIRE 16 -1 (450 -125)(200 -125);
WIRE 16 -1 (450 -75)(450 -125);
WIRE 16 -1 (200 -175)(450 -175);
WIRE 16 -1 (450 -175)(450 -125);
WIRE 16 -1 (450 -225)(200 -225);
WIRE 16 -1 (450 -175)(450 -225);
WIRE 16 -1 (450 -275)(200 -275);
WIRE 16 -1 (450 -225)(450 -275);
WIRE 16 -1 (450 -325)(200 -325);
WIRE 16 -1 (450 -275)(450 -325);
WIRE 16 -1 (450 -375)(200 -375);
WIRE 16 -1 (450 -325)(450 -375);
WIRE 16 -1 (200 -425)(450 -425);
WIRE 16 -1 (450 -425)(450 -375);
WIRE 16 -1 (450 -475)(450 -425);
WIRE 16 -1 (200 -475)(450 -475);
DOT 1 (1925 125);
DOT 1 (-2450 -425);
DOT 1 (-2450 -375);
DOT 1 (-2450 -325);
DOT 1 (-2450 -275);
DOT 1 (-2450 -175);
DOT 1 (-2450 -225);
DOT 1 (-2450 -125);
DOT 1 (-2450 -75);
DOT 1 (-2450 -25);
DOT 1 (-2450 25);
DOT 1 (-2450 75);
DOT 1 (-2450 125);
DOT 1 (-2450 175);
DOT 1 (-2450 225);
DOT 1 (-2450 275);
DOT 1 (-2450 325);
DOT 1 (-2450 375);
DOT 1 (-2450 425);
DOT 1 (-2450 475);
DOT 1 (-2450 525);
DOT 1 (-2450 575);
DOT 1 (-2450 625);
DOT 1 (-2450 675);
DOT 1 (-2450 725);
DOT 1 (-2450 775);
DOT 1 (-2450 825);
DOT 1 (-2450 875);
DOT 1 (-2450 925);
DOT 1 (-2450 975);
DOT 1 (-2450 1025);
DOT 1 (-2450 1075);
DOT 1 (-2450 1125);
DOT 1 (-2450 1175);
DOT 1 (-2450 1225);
DOT 1 (-2450 1275);
DOT 1 (-2450 1325);
DOT 1 (-2450 1375);
DOT 1 (-2450 1425);
DOT 1 (-2450 1475);
DOT 1 (-2450 1525);
DOT 1 (-2450 1575);
DOT 1 (-2450 1625);
DOT 1 (-2450 1675);
DOT 1 (-2450 1725);
DOT 1 (-2450 1775);
DOT 1 (-2450 1825);
DOT 1 (-2450 1875);
DOT 1 (-2450 1925);
DOT 1 (-2450 1975);
DOT 1 (-2450 2025);
DOT 1 (-2450 2075);
DOT 1 (-2450 2125);
DOT 1 (-2450 2175);
DOT 1 (-2450 2225);
DOT 1 (-2450 2275);
DOT 1 (-2450 2325);
DOT 1 (-2450 2375);
DOT 1 (-2450 2425);
DOT 1 (-2450 2475);
DOT 1 (-2450 2525);
DOT 1 (-2450 2575);
DOT 1 (-2450 2625);
DOT 1 (-2450 2675);
DOT 1 (-2450 2775);
DOT 1 (-2450 2725);
DOT 1 (-2450 2825);
DOT 1 (-2450 2875);
DOT 1 (-2450 2925);
DOT 1 (-2450 2975);
DOT 1 (-2450 3025);
DOT 1 (-2450 3075);
DOT 1 (-2450 3125);
DOT 1 (-2450 3175);
DOT 1 (-2450 3225);
DOT 1 (450 -425);
DOT 1 (450 -375);
DOT 1 (450 -325);
DOT 1 (450 -275);
DOT 1 (450 -225);
DOT 1 (450 -175);
DOT 1 (450 -125);
DOT 1 (450 -75);
DOT 1 (450 -25);
DOT 1 (1925 -425);
DOT 1 (1925 -375);
DOT 1 (1925 -325);
DOT 1 (1925 -275);
DOT 1 (1925 -225);
DOT 1 (1925 -125);
DOT 1 (1925 -75);
DOT 1 (1925 -25);
DOT 1 (1925 -175);
DOT 1 (4825 -425);
DOT 1 (4825 -375);
DOT 1 (4825 -325);
DOT 1 (4825 -275);
DOT 1 (4825 -175);
DOT 1 (4825 -225);
DOT 1 (4825 -125);
DOT 1 (4825 -75);
DOT 1 (4825 -25);
DOT 1 (450 125);
DOT 1 (450 25);
DOT 1 (450 75);
DOT 1 (450 225);
DOT 1 (450 175);
DOT 1 (450 325);
DOT 1 (450 375);
DOT 1 (450 275);
DOT 1 (450 425);
DOT 1 (450 475);
DOT 1 (450 525);
DOT 1 (450 625);
DOT 1 (450 575);
DOT 1 (450 725);
DOT 1 (450 675);
DOT 1 (450 775);
DOT 1 (450 825);
DOT 1 (450 875);
DOT 1 (450 925);
DOT 1 (450 975);
DOT 1 (450 1025);
DOT 1 (450 1125);
DOT 1 (450 1075);
DOT 1 (450 1275);
DOT 1 (450 1225);
DOT 1 (450 1175);
DOT 1 (450 1375);
DOT 1 (450 1325);
DOT 1 (450 1475);
DOT 1 (450 1525);
DOT 1 (450 1425);
DOT 1 (450 1575);
DOT 1 (450 1625);
DOT 1 (450 1675);
DOT 1 (450 1725);
DOT 1 (450 1775);
DOT 1 (450 1875);
DOT 1 (450 1825);
DOT 1 (450 1925);
DOT 1 (450 1975);
DOT 1 (450 2025);
DOT 1 (1925 75);
DOT 1 (1925 175);
DOT 1 (1925 225);
DOT 1 (1925 25);
DOT 1 (1925 325);
DOT 1 (1925 375);
DOT 1 (1925 425);
DOT 1 (1925 475);
DOT 1 (1925 275);
DOT 1 (1925 525);
DOT 1 (1925 575);
DOT 1 (1925 625);
DOT 1 (1925 675);
DOT 1 (1925 725);
DOT 1 (1925 775);
DOT 1 (1925 825);
DOT 1 (1925 875);
DOT 1 (1925 925);
DOT 1 (1925 975);
DOT 1 (1925 1025);
DOT 1 (1925 1125);
DOT 1 (1925 1175);
DOT 1 (1925 1225);
DOT 1 (1925 1275);
DOT 1 (1925 1075);
DOT 1 (1925 1375);
DOT 1 (1925 1425);
DOT 1 (1925 1475);
DOT 1 (1925 1525);
DOT 1 (1925 1325);
DOT 1 (1925 1575);
DOT 1 (1925 1675);
DOT 1 (1925 1725);
DOT 1 (1925 1775);
DOT 1 (1925 1625);
DOT 1 (1925 1875);
DOT 1 (1925 1925);
DOT 1 (1925 1975);
DOT 1 (1925 2025);
DOT 1 (1925 1825);
DOT 1 (450 2175);
DOT 1 (450 2075);
DOT 1 (450 2125);
DOT 1 (450 2275);
DOT 1 (450 2225);
DOT 1 (450 2425);
DOT 1 (450 2375);
DOT 1 (450 2325);
DOT 1 (450 2475);
DOT 1 (450 2525);
DOT 1 (450 2575);
DOT 1 (450 2625);
DOT 1 (450 2775);
DOT 1 (450 2725);
DOT 1 (450 2825);
DOT 1 (450 2875);
DOT 1 (450 2925);
DOT 1 (450 2975);
DOT 1 (450 3025);
DOT 1 (450 3075);
DOT 1 (450 3175);
DOT 1 (450 3125);
DOT 1 (450 3225);
DOT 1 (1925 2125);
DOT 1 (1925 2175);
DOT 1 (1925 2225);
DOT 1 (1925 2275);
DOT 1 (1925 2075);
DOT 1 (1925 2375);
DOT 1 (1925 2425);
DOT 1 (1925 2475);
DOT 1 (1925 2525);
DOT 1 (1925 2325);
DOT 1 (1925 2625);
DOT 1 (1925 2675);
DOT 1 (1925 2775);
DOT 1 (1925 2725);
DOT 1 (1925 2575);
DOT 1 (1925 2825);
DOT 1 (1925 2875);
DOT 1 (1925 2925);
DOT 1 (1925 2975);
DOT 1 (1925 3025);
DOT 1 (1925 3075);
DOT 1 (1925 3125);
DOT 1 (1925 3175);
DOT 1 (1925 3225);
DOT 1 (4825 25);
DOT 1 (4825 75);
DOT 1 (4825 125);
DOT 1 (4825 175);
DOT 1 (4825 225);
DOT 1 (4825 275);
DOT 1 (4825 325);
DOT 1 (4825 375);
DOT 1 (4825 475);
DOT 1 (4825 425);
DOT 1 (4825 525);
DOT 1 (4825 575);
DOT 1 (4825 625);
DOT 1 (4825 675);
DOT 1 (4825 725);
DOT 1 (4825 775);
DOT 1 (4825 825);
DOT 1 (4825 875);
DOT 1 (4825 975);
DOT 1 (4825 925);
DOT 1 (4825 1025);
DOT 1 (4825 1075);
DOT 1 (4825 1125);
DOT 1 (4825 1175);
DOT 1 (4825 1225);
DOT 1 (4825 1275);
DOT 1 (4825 1325);
DOT 1 (4825 1375);
DOT 1 (4825 1425);
DOT 1 (4825 1475);
DOT 1 (4825 1525);
DOT 1 (4825 1575);
DOT 1 (4825 1625);
DOT 1 (4825 1675);
DOT 1 (4825 1725);
DOT 1 (4825 1775);
DOT 1 (4825 1825);
DOT 1 (4825 1875);
DOT 1 (4825 1925);
DOT 1 (4825 1975);
DOT 1 (4825 2025);
DOT 1 (4825 2075);
DOT 1 (4825 2125);
DOT 1 (4825 2175);
DOT 1 (4825 2225);
DOT 1 (4825 2275);
DOT 1 (4825 2325);
DOT 1 (4825 2375);
DOT 1 (4825 2425);
DOT 1 (4825 2525);
DOT 1 (4825 2475);
DOT 1 (4825 2575);
DOT 1 (4825 2625);
DOT 1 (4825 2675);
DOT 1 (4825 2725);
DOT 1 (4825 2775);
DOT 1 (4825 2825);
DOT 1 (4825 2875);
DOT 1 (4825 2925);
DOT 1 (4825 3025);
DOT 1 (4825 2975);
DOT 1 (4825 3075);
DOT 1 (4825 3125);
DOT 1 (4825 3175);
DOT 1 (4825 3225);
DOT 1 (450 2675);
QUIT
